G04 ================== begin FILE IDENTIFICATION RECORD ==================*
G04 Layout Name:  t6m_pdb_d_0928_1400_274.brd*
G04 Film Name:    sst.art*
G04 File Format:  Gerber RS274X*
G04 File Origin:  Cadence Allegro 16.3-S048*
G04 Origin Date:  Tue Nov 26 11:01:50 2013*
G04 *
G04 Layer:  BOARD GEOMETRY/OUTLINE*
G04 Layer:  DRAWING FORMAT/TITLE_BLOCK*
G04 Layer:  MANUFACTURING/TP_TEXT_TOP*
G04 Layer:  REF DES/SILKSCREEN_TOP*
G04 Layer:  PACKAGE GEOMETRY/SILKSCREEN_TOP*
G04 Layer:  MANUFACTURING/PHOTOPLOT_OUTLINE*
G04 Layer:  DRAWING FORMAT/TITLE_DATA_SST*
G04 Layer:  BOARD GEOMETRY/SILKSCREEN_TOP*
G04 *
G04 Offset:    (0.00 0.00)*
G04 Mirror:    No*
G04 Mode:      Positive*
G04 Rotation:  0*
G04 FullContactRelief:  No*
G04 UndefLineWidth:     6.00*
G04 ================== end FILE IDENTIFICATION RECORD ====================*
%FSLAX25Y25*MOIN*%
%IR0*IPPOS*OFA0.00000B0.00000*MIA0B0*SFA1.00000B1.00000*%
%ADD10C,.015*%
%ADD11C,.006*%
%ADD12C,.008*%
%ADD13C,.06212*%
G75*
%LPD*%
G75*
G36*
G01X3653Y206976D02*
X-1965Y204167D01*
Y209785D01*
X3653Y206976D01*
G37*
G36*
G01X17444Y432458D02*
X14635Y438076D01*
X20253D01*
X17444Y432458D01*
G37*
G36*
G01X9606Y607816D02*
X7521Y611986D01*
X11691D01*
X9606Y607816D01*
G37*
G36*
G01Y635179D02*
X7521Y639349D01*
X11691D01*
X9606Y635179D01*
G37*
G36*
G01X23970Y1033484D02*
X23014Y1041505D01*
X17746Y1038633D01*
X23970Y1033484D01*
G37*
G36*
G01X25893Y1414328D02*
X28893Y1421828D01*
X22893D01*
X25893Y1414328D01*
G37*
G36*
G01X9606Y1479864D02*
X7521Y1484034D01*
X11691D01*
X9606Y1479864D01*
G37*
G36*
G01Y1507226D02*
X7521Y1511396D01*
X11691D01*
X9606Y1507226D01*
G37*
G36*
G01X4004Y1613453D02*
X1359Y1612130D01*
Y1614776D01*
X4004Y1613453D01*
G37*
G36*
G01X16119Y1750370D02*
X9820D01*
Y1736197D01*
X16119D01*
Y1750370D01*
G37*
G36*
G01X4146Y1947357D02*
X982Y1945775D01*
Y1948939D01*
X4146Y1947357D01*
G37*
G36*
G01X4025Y2047590D02*
X3168Y2044464D01*
X1010Y2046400D01*
X4025Y2047590D01*
G37*
G36*
G01X45223Y1837737D02*
X40223D01*
X42823Y1831737D01*
X45223Y1837737D01*
G37*
G36*
G01X66817Y34953D02*
X72435Y37762D01*
Y32144D01*
X66817Y34953D01*
G37*
G36*
G01X94634Y163235D02*
X71012D01*
Y360085D01*
X94634D01*
Y163235D01*
G37*
G36*
G01X66751Y242890D02*
X70291Y244660D01*
Y241120D01*
X66751Y242890D01*
G37*
G36*
G01X70236Y518701D02*
X76854Y522010D01*
Y515392D01*
X70236Y518701D01*
G37*
G36*
G01X110204Y327252D02*
X99574Y330008D01*
Y324496D01*
X110204Y327252D01*
G37*
G36*
G01X109852Y676616D02*
X99222Y679372D01*
Y673860D01*
X109852Y676616D01*
G37*
G36*
G01X109059Y1024192D02*
X98429Y1026948D01*
Y1021436D01*
X109059Y1024192D01*
G37*
G36*
G01X110383Y1372168D02*
X99753Y1374924D01*
Y1369412D01*
X110383Y1372168D01*
G37*
G36*
G01X109115Y1720232D02*
X98485Y1722988D01*
Y1717476D01*
X109115Y1720232D01*
G37*
G36*
G01X110111Y2067916D02*
X99481Y2070672D01*
Y2065160D01*
X110111Y2067916D01*
G37*
G36*
G01X196652Y56305D02*
G02Y89905I0J16800D01*
G01Y56305D01*
G37*
G36*
G01X197179Y135250D02*
G02Y168850I0J16800D01*
G01Y135250D01*
G37*
G36*
G01X197247Y230768D02*
G02Y264368I0J16800D01*
G01Y230768D01*
G37*
G36*
G01X197707Y314986D02*
G02Y348586I0J16800D01*
G01Y314986D01*
G37*
G36*
G01X196651Y404932D02*
G02Y438532I0J16800D01*
G01Y404932D01*
G37*
G36*
G01X197443Y489717D02*
G02Y523317I0J16800D01*
G01Y489717D01*
G37*
G36*
G01X199778Y581330D02*
G02Y614930I0J16800D01*
G01Y581330D01*
G37*
G36*
G01X197706Y664845D02*
G02Y698445I0J16800D01*
G01Y664845D01*
G37*
G36*
G01X198736Y757726D02*
G02Y791326I0J16800D01*
G01Y757726D01*
G37*
G36*
G01X198496Y839444D02*
G02Y873044I0J16800D01*
G01Y839444D01*
G37*
G36*
G01X203201Y930402D02*
G02Y964002I0J16800D01*
G01Y930402D01*
G37*
G36*
G01X202406Y1015744D02*
G02Y1049344I0J16800D01*
G01Y1015744D01*
G37*
G36*
G01X198140Y1106056D02*
G02Y1139656I0J16800D01*
G01Y1106056D01*
G37*
G36*
G01X198232Y1189433D02*
G02Y1223033I0J16800D01*
G01Y1189433D01*
G37*
G36*
G01X198736Y1282304D02*
G02Y1315904I0J16800D01*
G01Y1282304D01*
G37*
G36*
G01X197442Y1364166D02*
G02Y1397766I0J16800D01*
G01Y1364166D01*
G37*
G36*
G01X196353Y1457362D02*
G02Y1490962I0J16800D01*
G01Y1457362D01*
G37*
G36*
G01X197969Y1540477D02*
G02Y1574077I0J16800D01*
G01Y1540477D01*
G37*
G36*
G01X199033Y1631377D02*
G02Y1664977I0J16800D01*
G01Y1631377D01*
G37*
G36*
G01X198497Y1714551D02*
G02Y1748151I0J16800D01*
G01Y1714551D01*
G37*
G36*
G01X198420Y1806427D02*
G02Y1840027I0J16800D01*
G01Y1806427D01*
G37*
G36*
G01X197179Y1883620D02*
G02Y1917220I0J16800D01*
G01Y1883620D01*
G37*
G36*
G01X199015Y1981930D02*
G02Y2015530I0J16800D01*
G01Y1981930D01*
G37*
G36*
G01X198420Y2026588D02*
G02Y2060188I0J16800D01*
G01Y2026588D01*
G37*
%LPC*%
G75*
G54D13*
X189752Y73105D03*
X190279Y152050D03*
X190347Y247568D03*
X190807Y331786D03*
X189751Y421732D03*
X190543Y506517D03*
X192878Y598130D03*
X190806Y681645D03*
X191836Y774526D03*
X191596Y856244D03*
X196301Y947202D03*
X195506Y1032544D03*
X191240Y1122856D03*
X191332Y1206233D03*
X191836Y1299104D03*
X190542Y1380966D03*
X189453Y1474162D03*
X191069Y1557277D03*
X192133Y1648177D03*
X191597Y1731351D03*
X191520Y1823227D03*
X190279Y1900420D03*
X192115Y1998730D03*
X191520Y2043388D03*
%LPD*%
G75*
G54D10*
G01X17411Y150742D02*
X16661Y151242D01*
X15786Y151575D01*
X14786D01*
X13661Y151075D01*
X12786Y150242D01*
X12161Y149242D01*
X11661Y147575D01*
X11536Y146075D01*
X11786Y144575D01*
X12161Y143575D01*
X12911Y142575D01*
X13786Y141908D01*
X14661Y141575D01*
X15536D01*
X16411Y141908D01*
X17161Y142408D01*
X17786Y143075D01*
G01X23161Y141575D02*
X22161Y141742D01*
X21286Y142408D01*
X20536Y143408D01*
X20036Y144575D01*
X19786Y145908D01*
Y147242D01*
X20036Y148575D01*
X20536Y149742D01*
X21286Y150742D01*
X22161Y151408D01*
X23161Y151575D01*
X24161Y151408D01*
X25036Y150742D01*
X25786Y149742D01*
X26286Y148575D01*
X26536Y147242D01*
Y145908D01*
X26286Y144575D01*
X25786Y143408D01*
X25036Y142408D01*
X24161Y141742D01*
X23161Y141575D01*
G01X28411D02*
Y151575D01*
X31661Y143242D01*
X34911Y151575D01*
Y141575D01*
G01X37786Y149908D02*
X38536Y150908D01*
X39411Y151408D01*
X40411Y151575D01*
X41661Y151242D01*
X42536Y150408D01*
X42786Y149408D01*
X42661Y148408D01*
X42161Y147575D01*
X39661Y145908D01*
X38536Y144742D01*
X37786Y143075D01*
X37536Y141575D01*
X42786D01*
G01X23930Y312086D02*
X23180Y312586D01*
X22305Y312919D01*
X21305D01*
X20180Y312419D01*
X19305Y311586D01*
X18680Y310586D01*
X18180Y308919D01*
X18055Y307419D01*
X18305Y305919D01*
X18680Y304919D01*
X19430Y303919D01*
X20305Y303252D01*
X21180Y302919D01*
X22055D01*
X22930Y303252D01*
X23680Y303752D01*
X24305Y304419D01*
G01X29680Y302919D02*
X28680Y303086D01*
X27805Y303752D01*
X27055Y304752D01*
X26555Y305919D01*
X26305Y307252D01*
Y308586D01*
X26555Y309919D01*
X27055Y311086D01*
X27805Y312086D01*
X28680Y312752D01*
X29680Y312919D01*
X30680Y312752D01*
X31555Y312086D01*
X32305Y311086D01*
X32805Y309919D01*
X33055Y308586D01*
Y307252D01*
X32805Y305919D01*
X32305Y304752D01*
X31555Y303752D01*
X30680Y303086D01*
X29680Y302919D01*
G01X34930D02*
Y312919D01*
X38180Y304586D01*
X41430Y312919D01*
Y302919D01*
G01X43930Y304419D02*
X44680Y303586D01*
X45555Y303086D01*
X46680Y302919D01*
X47805Y303252D01*
X48680Y303919D01*
X49305Y305086D01*
X49430Y306419D01*
X49180Y307752D01*
X48555Y308586D01*
X47680Y309252D01*
X46805Y309419D01*
X45930Y309252D01*
X44805Y308586D01*
X45180Y312919D01*
X48555D01*
G01X8435Y646716D02*
X9435Y645883D01*
X10560Y645383D01*
X11560D01*
X12560Y645883D01*
X13310Y646716D01*
X13685Y647883D01*
X13435Y649049D01*
X12810Y650050D01*
X11685Y650716D01*
X10185Y651050D01*
X9310Y651716D01*
X8935Y652883D01*
X9185Y654050D01*
X9810Y654883D01*
X10685Y655383D01*
X11560D01*
X12435Y655050D01*
X13185Y654216D01*
G01X15810Y655383D02*
X17560Y645383D01*
X19560Y655383D01*
X21560Y645383D01*
X23310Y655383D01*
G01X25310Y647383D02*
X26060Y646216D01*
X27060Y645550D01*
X28185Y645383D01*
X29185Y645550D01*
X30185Y646383D01*
X30810Y647383D01*
X30935Y648383D01*
X30685Y649549D01*
X29810Y650383D01*
X28935Y650716D01*
X27810D01*
G01X28935D02*
X29685Y651216D01*
X30310Y652049D01*
X30560Y653050D01*
X30310Y654050D01*
X29685Y654883D01*
X28560Y655383D01*
X27435Y655216D01*
X26310Y654550D01*
G01X6931Y1449423D02*
X7931Y1448590D01*
X9056Y1448090D01*
X10056D01*
X11056Y1448590D01*
X11806Y1449423D01*
X12181Y1450590D01*
X11931Y1451756D01*
X11306Y1452757D01*
X10181Y1453423D01*
X8681Y1453757D01*
X7806Y1454423D01*
X7431Y1455590D01*
X7681Y1456757D01*
X8306Y1457590D01*
X9181Y1458090D01*
X10056D01*
X10931Y1457757D01*
X11681Y1456923D01*
G01X14306Y1458090D02*
X16056Y1448090D01*
X18056Y1458090D01*
X20056Y1448090D01*
X21806Y1458090D01*
G01X24181Y1456423D02*
X24931Y1457423D01*
X25806Y1457923D01*
X26806Y1458090D01*
X28056Y1457757D01*
X28931Y1456923D01*
X29181Y1455923D01*
X29056Y1454923D01*
X28556Y1454090D01*
X26056Y1452423D01*
X24931Y1451257D01*
X24181Y1449590D01*
X23931Y1448090D01*
X29181D01*
G01X5266Y1518403D02*
X6266Y1517570D01*
X7391Y1517070D01*
X8391D01*
X9391Y1517570D01*
X10141Y1518403D01*
X10516Y1519570D01*
X10266Y1520736D01*
X9641Y1521737D01*
X8516Y1522403D01*
X7016Y1522737D01*
X6141Y1523403D01*
X5766Y1524570D01*
X6016Y1525737D01*
X6641Y1526570D01*
X7516Y1527070D01*
X8391D01*
X9266Y1526737D01*
X10016Y1525903D01*
G01X12641Y1527070D02*
X14391Y1517070D01*
X16391Y1527070D01*
X18391Y1517070D01*
X20141Y1527070D01*
G01X24891Y1517070D02*
Y1527070D01*
X23391Y1525070D01*
G01Y1517070D02*
X26391D01*
G01X33872Y613467D02*
X33122Y613967D01*
X32247Y614300D01*
X31247D01*
X30122Y613800D01*
X29247Y612967D01*
X28622Y611967D01*
X28122Y610300D01*
X27997Y608800D01*
X28247Y607300D01*
X28622Y606300D01*
X29372Y605300D01*
X30247Y604633D01*
X31122Y604300D01*
X31997D01*
X32872Y604633D01*
X33622Y605133D01*
X34247Y605800D01*
G01X36372Y604300D02*
Y614300D01*
X39622Y605967D01*
X42872Y614300D01*
Y604300D01*
G01X44372Y600967D02*
X51872D01*
G01X54122Y604300D02*
Y614300D01*
X57122D01*
X58122Y613800D01*
X58872Y612633D01*
X59122Y611300D01*
X58872Y609967D01*
X58247Y608967D01*
X57122Y608466D01*
X54122D01*
G01X61372Y614300D02*
X63122Y604300D01*
X65122Y614300D01*
X67122Y604300D01*
X68872Y614300D01*
G01X71122Y604300D02*
Y614300D01*
X74247D01*
X75247Y613800D01*
X75872Y613133D01*
X76122Y611800D01*
X75872Y610467D01*
X75122Y609633D01*
X74247Y609133D01*
X71122D01*
G01X74247D02*
X76122Y604300D01*
G01X78372Y600967D02*
X85872D01*
G01X93372Y613467D02*
X92622Y613967D01*
X91747Y614300D01*
X90747D01*
X89622Y613800D01*
X88747Y612967D01*
X88122Y611967D01*
X87622Y610300D01*
X87497Y608800D01*
X87747Y607300D01*
X88122Y606300D01*
X88872Y605300D01*
X89747Y604633D01*
X90622Y604300D01*
X91497D01*
X92372Y604633D01*
X93122Y605133D01*
X93747Y605800D01*
G01X99122Y614300D02*
Y604300D01*
G01X96247Y614300D02*
X101997D01*
G01X105122D02*
Y604300D01*
X110122D01*
G01X70194Y50291D02*
X69694Y49541D01*
X69361Y48666D01*
Y47666D01*
X69861Y46541D01*
X70694Y45666D01*
X71694Y45041D01*
X73361Y44541D01*
X74861Y44416D01*
X76361Y44666D01*
X77361Y45041D01*
X78361Y45791D01*
X79028Y46666D01*
X79361Y47541D01*
Y48416D01*
X79028Y49291D01*
X78528Y50041D01*
X77861Y50666D01*
G01X79361Y56041D02*
X79194Y55041D01*
X78528Y54166D01*
X77528Y53416D01*
X76361Y52916D01*
X75028Y52666D01*
X73694D01*
X72361Y52916D01*
X71194Y53416D01*
X70194Y54166D01*
X69528Y55041D01*
X69361Y56041D01*
X69528Y57041D01*
X70194Y57916D01*
X71194Y58666D01*
X72361Y59166D01*
X73694Y59416D01*
X75028D01*
X76361Y59166D01*
X77528Y58666D01*
X78528Y57916D01*
X79194Y57041D01*
X79361Y56041D01*
G01Y61291D02*
X69361D01*
X77694Y64541D01*
X69361Y67791D01*
X79361D01*
G01Y73041D02*
X69361D01*
X71361Y71541D01*
G01X79361D02*
Y74541D01*
G01X73453Y383301D02*
X72953Y382551D01*
X72620Y381676D01*
Y380676D01*
X73120Y379551D01*
X73953Y378676D01*
X74953Y378051D01*
X76620Y377551D01*
X78120Y377426D01*
X79620Y377676D01*
X80620Y378051D01*
X81620Y378801D01*
X82287Y379676D01*
X82620Y380551D01*
Y381426D01*
X82287Y382301D01*
X81787Y383051D01*
X81120Y383676D01*
G01X82620Y389051D02*
X82453Y388051D01*
X81787Y387176D01*
X80787Y386426D01*
X79620Y385926D01*
X78287Y385676D01*
X76953D01*
X75620Y385926D01*
X74453Y386426D01*
X73453Y387176D01*
X72787Y388051D01*
X72620Y389051D01*
X72787Y390051D01*
X73453Y390926D01*
X74453Y391676D01*
X75620Y392176D01*
X76953Y392426D01*
X78287D01*
X79620Y392176D01*
X80787Y391676D01*
X81787Y390926D01*
X82453Y390051D01*
X82620Y389051D01*
G01Y394301D02*
X72620D01*
X80953Y397551D01*
X72620Y400801D01*
X82620D01*
G01X78454Y403676D02*
X77287Y404551D01*
X76620Y405301D01*
X76287Y406301D01*
X76620Y407176D01*
X77287Y407801D01*
X78287Y408301D01*
X79453Y408426D01*
X80453Y408301D01*
X81454Y407801D01*
X82287Y407051D01*
X82620Y406176D01*
X82287Y405176D01*
X81287Y404301D01*
X79787Y403801D01*
X78120Y403676D01*
X75954Y403926D01*
X74787Y404301D01*
X73620Y404926D01*
X72787Y405801D01*
X72620Y406676D01*
X72953Y407551D01*
X73787Y408176D01*
G01X73706Y543198D02*
X83706D01*
Y548198D01*
G01Y551073D02*
X73706Y554198D01*
X83706Y557323D01*
G01X80206Y556198D02*
Y552198D01*
G01X83706Y559823D02*
X73706D01*
X83706Y565573D01*
X73706D01*
G01X83706Y571198D02*
X73706D01*
X75706Y569698D01*
G01X83706D02*
Y572698D01*
G01X52607Y1012839D02*
X52107Y1012089D01*
X51774Y1011214D01*
Y1010214D01*
X52274Y1009089D01*
X53107Y1008214D01*
X54107Y1007589D01*
X55774Y1007089D01*
X57274Y1006964D01*
X58774Y1007214D01*
X59774Y1007589D01*
X60774Y1008339D01*
X61441Y1009214D01*
X61774Y1010089D01*
Y1010964D01*
X61441Y1011839D01*
X60941Y1012589D01*
X60274Y1013214D01*
G01X61774Y1015339D02*
X51774D01*
X60107Y1018589D01*
X51774Y1021839D01*
X61774D01*
G01X52607Y1038339D02*
X52107Y1037589D01*
X51774Y1036714D01*
Y1035714D01*
X52274Y1034589D01*
X53107Y1033714D01*
X54107Y1033089D01*
X55774Y1032589D01*
X57274Y1032464D01*
X58774Y1032714D01*
X59774Y1033089D01*
X60774Y1033839D01*
X61441Y1034714D01*
X61774Y1035589D01*
Y1036464D01*
X61441Y1037339D01*
X60941Y1038089D01*
X60274Y1038714D01*
G01X61774Y1044089D02*
X61607Y1043089D01*
X60941Y1042214D01*
X59941Y1041464D01*
X58774Y1040964D01*
X57441Y1040714D01*
X56107D01*
X54774Y1040964D01*
X53607Y1041464D01*
X52607Y1042214D01*
X51941Y1043089D01*
X51774Y1044089D01*
X51941Y1045089D01*
X52607Y1045964D01*
X53607Y1046714D01*
X54774Y1047214D01*
X56107Y1047464D01*
X57441D01*
X58774Y1047214D01*
X59941Y1046714D01*
X60941Y1045964D01*
X61607Y1045089D01*
X61774Y1044089D01*
G01Y1049714D02*
X51774D01*
X61774Y1055464D01*
X51774D01*
G01X61774Y1058214D02*
X51774D01*
X61774Y1063964D01*
X51774D01*
G01X61774Y1078089D02*
X51774D01*
X53774Y1076589D01*
G01X61774D02*
Y1079589D01*
G01Y1091964D02*
X51774Y1095089D01*
X61774Y1098214D01*
G01X58274Y1097089D02*
Y1093089D01*
G01X61774Y1100714D02*
X51774D01*
X61774Y1106464D01*
X51774D01*
G01X61774Y1109339D02*
X51774D01*
Y1111839D01*
X52274Y1112839D01*
X52941Y1113589D01*
X53941Y1114214D01*
X55108Y1114714D01*
X56774Y1114839D01*
X58441Y1114714D01*
X59607Y1114214D01*
X60608Y1113589D01*
X61274Y1112839D01*
X61774Y1111839D01*
Y1109339D01*
G01X53441Y1126714D02*
X52441Y1127464D01*
X51941Y1128339D01*
X51774Y1129339D01*
X52107Y1130589D01*
X52941Y1131464D01*
X53941Y1131714D01*
X54941Y1131589D01*
X55774Y1131089D01*
X57441Y1128589D01*
X58607Y1127464D01*
X60274Y1126714D01*
X61774Y1126464D01*
Y1131714D01*
G01X68125Y1785564D02*
X58125D01*
Y1790314D01*
G01X62958Y1788564D02*
Y1785564D01*
G01X68125Y1793314D02*
X58125Y1796439D01*
X68125Y1799564D01*
G01X64625Y1798439D02*
Y1794439D01*
G01X68125Y1802064D02*
X58125D01*
X68125Y1807814D01*
X58125D01*
G01X72040Y1785218D02*
X71540Y1784468D01*
X71207Y1783593D01*
Y1782593D01*
X71707Y1781468D01*
X72540Y1780593D01*
X73540Y1779968D01*
X75207Y1779468D01*
X76707Y1779343D01*
X78207Y1779593D01*
X79207Y1779968D01*
X80207Y1780718D01*
X80874Y1781593D01*
X81207Y1782468D01*
Y1783343D01*
X80874Y1784218D01*
X80374Y1784968D01*
X79707Y1785593D01*
G01X81207Y1790968D02*
X81040Y1789968D01*
X80374Y1789093D01*
X79374Y1788343D01*
X78207Y1787843D01*
X76874Y1787593D01*
X75540D01*
X74207Y1787843D01*
X73040Y1788343D01*
X72040Y1789093D01*
X71374Y1789968D01*
X71207Y1790968D01*
X71374Y1791968D01*
X72040Y1792843D01*
X73040Y1793593D01*
X74207Y1794093D01*
X75540Y1794343D01*
X76874D01*
X78207Y1794093D01*
X79374Y1793593D01*
X80374Y1792843D01*
X81040Y1791968D01*
X81207Y1790968D01*
G01Y1796593D02*
X71207D01*
X81207Y1802343D01*
X71207D01*
G01X81207Y1805093D02*
X71207D01*
X81207Y1810843D01*
X71207D01*
G01X83349Y2001179D02*
X73349D01*
Y2004304D01*
X73849Y2005304D01*
X74516Y2005929D01*
X75849Y2006179D01*
X77182Y2005929D01*
X78016Y2005179D01*
X78516Y2004304D01*
Y2001179D01*
G01Y2004304D02*
X83349Y2006179D01*
G01Y2014679D02*
Y2009679D01*
X73349D01*
Y2014679D01*
G01X78182Y2012679D02*
Y2009679D01*
G01X83349Y2017429D02*
X73349D01*
X81682Y2020679D01*
X73349Y2023929D01*
X83349D01*
G01Y2029179D02*
X83182Y2028179D01*
X82516Y2027304D01*
X81516Y2026554D01*
X80349Y2026054D01*
X79016Y2025804D01*
X77682D01*
X76349Y2026054D01*
X75182Y2026554D01*
X74182Y2027304D01*
X73516Y2028179D01*
X73349Y2029179D01*
X73516Y2030179D01*
X74182Y2031054D01*
X75182Y2031804D01*
X76349Y2032304D01*
X77682Y2032554D01*
X79016D01*
X80349Y2032304D01*
X81516Y2031804D01*
X82516Y2031054D01*
X83182Y2030179D01*
X83349Y2029179D01*
G01X73349Y2037679D02*
X83349D01*
G01X73349Y2034804D02*
Y2040554D01*
G01X83349Y2048679D02*
Y2043679D01*
X73349D01*
Y2048679D01*
G01X78182Y2046679D02*
Y2043679D01*
G01X77868Y1582305D02*
X87868D01*
Y1587305D01*
G01Y1590180D02*
X77868Y1593305D01*
X87868Y1596430D01*
G01X84368Y1595305D02*
Y1591305D01*
G01X87868Y1598930D02*
X77868D01*
X87868Y1604680D01*
X77868D01*
G01X79535Y1607930D02*
X78535Y1608680D01*
X78035Y1609555D01*
X77868Y1610555D01*
X78201Y1611805D01*
X79035Y1612680D01*
X80035Y1612930D01*
X81035Y1612805D01*
X81868Y1612305D01*
X83535Y1609805D01*
X84701Y1608680D01*
X86368Y1607930D01*
X87868Y1607680D01*
Y1612930D01*
G01X90832Y1919848D02*
X90332Y1919098D01*
X89999Y1918223D01*
Y1917223D01*
X90499Y1916098D01*
X91332Y1915223D01*
X92332Y1914598D01*
X93999Y1914098D01*
X95499Y1913973D01*
X96999Y1914223D01*
X97999Y1914598D01*
X98999Y1915348D01*
X99666Y1916223D01*
X99999Y1917098D01*
Y1917973D01*
X99666Y1918848D01*
X99166Y1919598D01*
X98499Y1920223D01*
G01X99999Y1925598D02*
X99832Y1924598D01*
X99166Y1923723D01*
X98166Y1922973D01*
X96999Y1922473D01*
X95666Y1922223D01*
X94332D01*
X92999Y1922473D01*
X91832Y1922973D01*
X90832Y1923723D01*
X90166Y1924598D01*
X89999Y1925598D01*
X90166Y1926598D01*
X90832Y1927473D01*
X91832Y1928223D01*
X92999Y1928723D01*
X94332Y1928973D01*
X95666D01*
X96999Y1928723D01*
X98166Y1928223D01*
X99166Y1927473D01*
X99832Y1926598D01*
X99999Y1925598D01*
G01Y1930848D02*
X89999D01*
X98332Y1934098D01*
X89999Y1937348D01*
X99999D01*
G01X98499Y1939848D02*
X99332Y1940598D01*
X99832Y1941473D01*
X99999Y1942598D01*
X99666Y1943723D01*
X98999Y1944598D01*
X97832Y1945223D01*
X96499Y1945348D01*
X95166Y1945098D01*
X94332Y1944473D01*
X93666Y1943598D01*
X93499Y1942723D01*
X93666Y1941848D01*
X94332Y1940723D01*
X89999Y1941098D01*
Y1944473D01*
G01X85251Y1907224D02*
X75251D01*
Y1910349D01*
X75751Y1911349D01*
X76418Y1911974D01*
X77751Y1912224D01*
X79084Y1911974D01*
X79918Y1911224D01*
X80418Y1910349D01*
Y1907224D01*
G01Y1910349D02*
X85251Y1912224D01*
G01Y1920724D02*
Y1915724D01*
X75251D01*
Y1920724D01*
G01X80084Y1918724D02*
Y1915724D01*
G01X85251Y1923474D02*
X75251D01*
X83584Y1926724D01*
X75251Y1929974D01*
X85251D01*
G01Y1935224D02*
X85084Y1934224D01*
X84418Y1933349D01*
X83418Y1932599D01*
X82251Y1932099D01*
X80918Y1931849D01*
X79584D01*
X78251Y1932099D01*
X77084Y1932599D01*
X76084Y1933349D01*
X75418Y1934224D01*
X75251Y1935224D01*
X75418Y1936224D01*
X76084Y1937099D01*
X77084Y1937849D01*
X78251Y1938349D01*
X79584Y1938599D01*
X80918D01*
X82251Y1938349D01*
X83418Y1937849D01*
X84418Y1937099D01*
X85084Y1936224D01*
X85251Y1935224D01*
G01X75251Y1943724D02*
X85251D01*
G01X75251Y1940849D02*
Y1946599D01*
G01X85251Y1954724D02*
Y1949724D01*
X75251D01*
Y1954724D01*
G01X80084Y1952724D02*
Y1949724D01*
G01X90119Y2012851D02*
X89619Y2012101D01*
X89286Y2011226D01*
Y2010226D01*
X89786Y2009101D01*
X90619Y2008226D01*
X91619Y2007601D01*
X93286Y2007101D01*
X94786Y2006976D01*
X96286Y2007226D01*
X97286Y2007601D01*
X98286Y2008351D01*
X98953Y2009226D01*
X99286Y2010101D01*
Y2010976D01*
X98953Y2011851D01*
X98453Y2012601D01*
X97786Y2013226D01*
G01X99286Y2018601D02*
X99119Y2017601D01*
X98453Y2016726D01*
X97453Y2015976D01*
X96286Y2015476D01*
X94953Y2015226D01*
X93619D01*
X92286Y2015476D01*
X91119Y2015976D01*
X90119Y2016726D01*
X89453Y2017601D01*
X89286Y2018601D01*
X89453Y2019601D01*
X90119Y2020476D01*
X91119Y2021226D01*
X92286Y2021726D01*
X93619Y2021976D01*
X94953D01*
X96286Y2021726D01*
X97453Y2021226D01*
X98453Y2020476D01*
X99119Y2019601D01*
X99286Y2018601D01*
G01Y2023851D02*
X89286D01*
X97619Y2027101D01*
X89286Y2030351D01*
X99286D01*
G01X95120Y2033226D02*
X93953Y2034101D01*
X93286Y2034851D01*
X92953Y2035851D01*
X93286Y2036726D01*
X93953Y2037351D01*
X94953Y2037851D01*
X96119Y2037976D01*
X97119Y2037851D01*
X98120Y2037351D01*
X98953Y2036601D01*
X99286Y2035726D01*
X98953Y2034726D01*
X97953Y2033851D01*
X96453Y2033351D01*
X94786Y2033226D01*
X92620Y2033476D01*
X91453Y2033851D01*
X90286Y2034476D01*
X89453Y2035351D01*
X89286Y2036226D01*
X89619Y2037101D01*
X90453Y2037726D01*
G01X161372Y275332D02*
X151372D01*
Y278332D01*
X151872Y279332D01*
X153039Y280082D01*
X154372Y280332D01*
X155705Y280082D01*
X156705Y279457D01*
X157206Y278332D01*
Y275332D01*
G01X160039Y283707D02*
X160872Y284707D01*
X161372Y285832D01*
Y286832D01*
X160872Y287832D01*
X160039Y288582D01*
X158872Y288957D01*
X157706Y288707D01*
X156705Y288082D01*
X156039Y286957D01*
X155705Y285457D01*
X155039Y284582D01*
X153872Y284207D01*
X152705Y284457D01*
X151872Y285082D01*
X151372Y285957D01*
Y286832D01*
X151705Y287707D01*
X152539Y288457D01*
G01X151372Y292082D02*
X158539D01*
X160039Y292582D01*
X161039Y293582D01*
X161372Y294832D01*
X161039Y296082D01*
X160039Y297082D01*
X158539Y297582D01*
X151372D01*
G01X161372Y303332D02*
X151372D01*
X153372Y301832D01*
G01X161372D02*
Y304832D01*
G01X169530Y657575D02*
X159530D01*
Y660575D01*
X160030Y661575D01*
X161197Y662325D01*
X162530Y662575D01*
X163863Y662325D01*
X164863Y661700D01*
X165364Y660575D01*
Y657575D01*
G01X168197Y665950D02*
X169030Y666950D01*
X169530Y668075D01*
Y669075D01*
X169030Y670075D01*
X168197Y670825D01*
X167030Y671200D01*
X165864Y670950D01*
X164863Y670325D01*
X164197Y669200D01*
X163863Y667700D01*
X163197Y666825D01*
X162030Y666450D01*
X160863Y666700D01*
X160030Y667325D01*
X159530Y668200D01*
Y669075D01*
X159863Y669950D01*
X160697Y670700D01*
G01X159530Y674325D02*
X166697D01*
X168197Y674825D01*
X169197Y675825D01*
X169530Y677075D01*
X169197Y678325D01*
X168197Y679325D01*
X166697Y679825D01*
X159530D01*
G01X161197Y683200D02*
X160197Y683950D01*
X159697Y684825D01*
X159530Y685825D01*
X159863Y687075D01*
X160697Y687950D01*
X161697Y688200D01*
X162697Y688075D01*
X163530Y687575D01*
X165197Y685075D01*
X166363Y683950D01*
X168030Y683200D01*
X169530Y682950D01*
Y688200D01*
G01X160813Y983924D02*
X150813D01*
Y986924D01*
X151313Y987924D01*
X152480Y988674D01*
X153813Y988924D01*
X155146Y988674D01*
X156146Y988049D01*
X156647Y986924D01*
Y983924D01*
G01X159480Y992299D02*
X160313Y993299D01*
X160813Y994424D01*
Y995424D01*
X160313Y996424D01*
X159480Y997174D01*
X158313Y997549D01*
X157147Y997299D01*
X156146Y996674D01*
X155480Y995549D01*
X155146Y994049D01*
X154480Y993174D01*
X153313Y992799D01*
X152146Y993049D01*
X151313Y993674D01*
X150813Y994549D01*
Y995424D01*
X151146Y996299D01*
X151980Y997049D01*
G01X150813Y1000674D02*
X157980D01*
X159480Y1001174D01*
X160480Y1002174D01*
X160813Y1003424D01*
X160480Y1004674D01*
X159480Y1005674D01*
X157980Y1006174D01*
X150813D01*
G01X158813Y1009174D02*
X159980Y1009924D01*
X160646Y1010924D01*
X160813Y1012049D01*
X160646Y1013049D01*
X159813Y1014049D01*
X158813Y1014674D01*
X157813Y1014799D01*
X156647Y1014549D01*
X155813Y1013674D01*
X155480Y1012799D01*
Y1011674D01*
G01Y1012799D02*
X154980Y1013549D01*
X154147Y1014174D01*
X153146Y1014424D01*
X152146Y1014174D01*
X151313Y1013549D01*
X150813Y1012424D01*
X150980Y1011299D01*
X151646Y1010174D01*
G01X170389Y1355971D02*
X160389D01*
Y1358971D01*
X160889Y1359971D01*
X162056Y1360721D01*
X163389Y1360971D01*
X164722Y1360721D01*
X165722Y1360096D01*
X166223Y1358971D01*
Y1355971D01*
G01X169056Y1364346D02*
X169889Y1365346D01*
X170389Y1366471D01*
Y1367471D01*
X169889Y1368471D01*
X169056Y1369221D01*
X167889Y1369596D01*
X166723Y1369346D01*
X165722Y1368721D01*
X165056Y1367596D01*
X164722Y1366096D01*
X164056Y1365221D01*
X162889Y1364846D01*
X161722Y1365096D01*
X160889Y1365721D01*
X160389Y1366596D01*
Y1367471D01*
X160722Y1368346D01*
X161556Y1369096D01*
G01X160389Y1372721D02*
X167556D01*
X169056Y1373221D01*
X170056Y1374221D01*
X170389Y1375471D01*
X170056Y1376721D01*
X169056Y1377721D01*
X167556Y1378221D01*
X160389D01*
G01X170389Y1385471D02*
X160389D01*
X167556Y1380846D01*
Y1387096D01*
G01X173022Y1690056D02*
X163022D01*
Y1693056D01*
X163522Y1694056D01*
X164689Y1694806D01*
X166022Y1695056D01*
X167355Y1694806D01*
X168355Y1694181D01*
X168856Y1693056D01*
Y1690056D01*
G01X171689Y1698431D02*
X172522Y1699431D01*
X173022Y1700556D01*
Y1701556D01*
X172522Y1702556D01*
X171689Y1703306D01*
X170522Y1703681D01*
X169356Y1703431D01*
X168355Y1702806D01*
X167689Y1701681D01*
X167355Y1700181D01*
X166689Y1699306D01*
X165522Y1698931D01*
X164355Y1699181D01*
X163522Y1699806D01*
X163022Y1700681D01*
Y1701556D01*
X163355Y1702431D01*
X164189Y1703181D01*
G01X163022Y1706806D02*
X170189D01*
X171689Y1707306D01*
X172689Y1708306D01*
X173022Y1709556D01*
X172689Y1710806D01*
X171689Y1711806D01*
X170189Y1712306D01*
X163022D01*
G01X171522Y1715306D02*
X172355Y1716056D01*
X172855Y1716931D01*
X173022Y1718056D01*
X172689Y1719181D01*
X172022Y1720056D01*
X170855Y1720681D01*
X169522Y1720806D01*
X168189Y1720556D01*
X167355Y1719931D01*
X166689Y1719056D01*
X166522Y1718181D01*
X166689Y1717306D01*
X167355Y1716181D01*
X163022Y1716556D01*
Y1719931D01*
G01X169692Y2040664D02*
X159692D01*
Y2043664D01*
X160192Y2044664D01*
X161359Y2045414D01*
X162692Y2045664D01*
X164025Y2045414D01*
X165025Y2044789D01*
X165526Y2043664D01*
Y2040664D01*
G01X168359Y2049039D02*
X169192Y2050039D01*
X169692Y2051164D01*
Y2052164D01*
X169192Y2053164D01*
X168359Y2053914D01*
X167192Y2054289D01*
X166026Y2054039D01*
X165025Y2053414D01*
X164359Y2052289D01*
X164025Y2050789D01*
X163359Y2049914D01*
X162192Y2049539D01*
X161025Y2049789D01*
X160192Y2050414D01*
X159692Y2051289D01*
Y2052164D01*
X160025Y2053039D01*
X160859Y2053789D01*
G01X159692Y2057414D02*
X166859D01*
X168359Y2057914D01*
X169359Y2058914D01*
X169692Y2060164D01*
X169359Y2061414D01*
X168359Y2062414D01*
X166859Y2062914D01*
X159692D01*
G01X165526Y2066289D02*
X164359Y2067164D01*
X163692Y2067914D01*
X163359Y2068914D01*
X163692Y2069789D01*
X164359Y2070414D01*
X165359Y2070914D01*
X166525Y2071039D01*
X167525Y2070914D01*
X168526Y2070414D01*
X169359Y2069664D01*
X169692Y2068789D01*
X169359Y2067789D01*
X168359Y2066914D01*
X166859Y2066414D01*
X165192Y2066289D01*
X163026Y2066539D01*
X161859Y2066914D01*
X160692Y2067539D01*
X159859Y2068414D01*
X159692Y2069289D01*
X160025Y2070164D01*
X160859Y2070789D01*
G01X258798Y83445D02*
Y73445D01*
G01X255923Y83445D02*
X261673D01*
G01X264798Y73445D02*
Y83445D01*
X267923D01*
X268923Y82945D01*
X269548Y82278D01*
X269798Y80945D01*
X269548Y79612D01*
X268798Y78778D01*
X267923Y78278D01*
X264798D01*
G01X267923D02*
X269798Y73445D01*
G01X272673D02*
X275798Y83445D01*
X278923Y73445D01*
G01X277798Y76945D02*
X273798D01*
G01X284298Y73445D02*
Y77945D01*
X281798Y83445D01*
G01X286798D02*
X284298Y77945D01*
G01X302298Y78778D02*
X302798Y79278D01*
X303173Y80111D01*
X303423Y81278D01*
X303173Y82278D01*
X302673Y82945D01*
X301798Y83445D01*
X298423D01*
Y73445D01*
X302548D01*
X303423Y74112D01*
X303923Y75112D01*
X304173Y76278D01*
X303923Y77445D01*
X303173Y78445D01*
X302298Y78778D01*
X298423D01*
G01X307298Y73445D02*
Y83445D01*
X310298D01*
X311298Y82945D01*
X312048Y81778D01*
X312298Y80445D01*
X312048Y79112D01*
X311423Y78112D01*
X310298Y77611D01*
X307298D01*
G01X326798Y73445D02*
Y83445D01*
X325298Y81445D01*
G01Y73445D02*
X328298D01*
G01X316522Y1555898D02*
Y1545898D01*
G01X313647Y1555898D02*
X319397D01*
G01X322522Y1545898D02*
Y1555898D01*
X325647D01*
X326647Y1555398D01*
X327272Y1554731D01*
X327522Y1553398D01*
X327272Y1552065D01*
X326522Y1551231D01*
X325647Y1550731D01*
X322522D01*
G01X325647D02*
X327522Y1545898D01*
G01X330397D02*
X333522Y1555898D01*
X336647Y1545898D01*
G01X335522Y1549398D02*
X331522D01*
G01X342022Y1545898D02*
Y1550398D01*
X339522Y1555898D01*
G01X344522D02*
X342022Y1550398D01*
G01X360022Y1551231D02*
X360522Y1551731D01*
X360897Y1552564D01*
X361147Y1553731D01*
X360897Y1554731D01*
X360397Y1555398D01*
X359522Y1555898D01*
X356147D01*
Y1545898D01*
X360272D01*
X361147Y1546565D01*
X361647Y1547565D01*
X361897Y1548731D01*
X361647Y1549898D01*
X360897Y1550898D01*
X360022Y1551231D01*
X356147D01*
G01X365022Y1545898D02*
Y1555898D01*
X368022D01*
X369022Y1555398D01*
X369772Y1554231D01*
X370022Y1552898D01*
X369772Y1551565D01*
X369147Y1550565D01*
X368022Y1550064D01*
X365022D01*
G01X384522Y1545898D02*
Y1555898D01*
X383022Y1553898D01*
G01Y1545898D02*
X386022D01*
G01X393022Y1555898D02*
X392022Y1555565D01*
X391272Y1554731D01*
X390772Y1553731D01*
X390397Y1552398D01*
X390272Y1550898D01*
X390397Y1549398D01*
X390772Y1548065D01*
X391272Y1547064D01*
X392022Y1546231D01*
X393022Y1545898D01*
X394022Y1546231D01*
X394772Y1547064D01*
X395272Y1548065D01*
X395647Y1549398D01*
X395772Y1550898D01*
X395647Y1552398D01*
X395272Y1553731D01*
X394772Y1554731D01*
X394022Y1555565D01*
X393022Y1555898D01*
G01X314592Y1739257D02*
Y1729257D01*
G01X311717Y1739257D02*
X317467D01*
G01X320592Y1729257D02*
Y1739257D01*
X323717D01*
X324717Y1738757D01*
X325342Y1738090D01*
X325592Y1736757D01*
X325342Y1735424D01*
X324592Y1734590D01*
X323717Y1734090D01*
X320592D01*
G01X323717D02*
X325592Y1729257D01*
G01X328467D02*
X331592Y1739257D01*
X334717Y1729257D01*
G01X333592Y1732757D02*
X329592D01*
G01X340092Y1729257D02*
Y1733757D01*
X337592Y1739257D01*
G01X342592D02*
X340092Y1733757D01*
G01X358092Y1734590D02*
X358592Y1735090D01*
X358967Y1735923D01*
X359217Y1737090D01*
X358967Y1738090D01*
X358467Y1738757D01*
X357592Y1739257D01*
X354217D01*
Y1729257D01*
X358342D01*
X359217Y1729924D01*
X359717Y1730924D01*
X359967Y1732090D01*
X359717Y1733257D01*
X358967Y1734257D01*
X358092Y1734590D01*
X354217D01*
G01X363092Y1729257D02*
Y1739257D01*
X366092D01*
X367092Y1738757D01*
X367842Y1737590D01*
X368092Y1736257D01*
X367842Y1734924D01*
X367217Y1733924D01*
X366092Y1733423D01*
X363092D01*
G01X382592Y1729257D02*
Y1739257D01*
X381092Y1737257D01*
G01Y1729257D02*
X384092D01*
G01X391092D02*
Y1739257D01*
X389592Y1737257D01*
G01Y1729257D02*
X392592D01*
G01X320912Y166746D02*
Y156746D01*
G01X318037Y166746D02*
X323787D01*
G01X326912Y156746D02*
Y166746D01*
X330037D01*
X331037Y166246D01*
X331662Y165579D01*
X331912Y164246D01*
X331662Y162913D01*
X330912Y162079D01*
X330037Y161579D01*
X326912D01*
G01X330037D02*
X331912Y156746D01*
G01X334787D02*
X337912Y166746D01*
X341037Y156746D01*
G01X339912Y160246D02*
X335912D01*
G01X346412Y156746D02*
Y161246D01*
X343912Y166746D01*
G01X348912D02*
X346412Y161246D01*
G01X364412Y162079D02*
X364912Y162579D01*
X365287Y163412D01*
X365537Y164579D01*
X365287Y165579D01*
X364787Y166246D01*
X363912Y166746D01*
X360537D01*
Y156746D01*
X364662D01*
X365537Y157413D01*
X366037Y158413D01*
X366287Y159579D01*
X366037Y160746D01*
X365287Y161746D01*
X364412Y162079D01*
X360537D01*
G01X369412Y156746D02*
Y166746D01*
X372412D01*
X373412Y166246D01*
X374162Y165079D01*
X374412Y163746D01*
X374162Y162413D01*
X373537Y161413D01*
X372412Y160912D01*
X369412D01*
G01X386537Y165079D02*
X387287Y166079D01*
X388162Y166579D01*
X389162Y166746D01*
X390412Y166413D01*
X391287Y165579D01*
X391537Y164579D01*
X391412Y163579D01*
X390912Y162746D01*
X388412Y161079D01*
X387287Y159913D01*
X386537Y158246D01*
X386287Y156746D01*
X391537D01*
G01X329647Y339167D02*
Y329167D01*
G01X326772Y339167D02*
X332522D01*
G01X335647Y329167D02*
Y339167D01*
X338772D01*
X339772Y338667D01*
X340397Y338000D01*
X340647Y336667D01*
X340397Y335334D01*
X339647Y334500D01*
X338772Y334000D01*
X335647D01*
G01X338772D02*
X340647Y329167D01*
G01X343522D02*
X346647Y339167D01*
X349772Y329167D01*
G01X348647Y332667D02*
X344647D01*
G01X355147Y329167D02*
Y333667D01*
X352647Y339167D01*
G01X357647D02*
X355147Y333667D01*
G01X373147Y334500D02*
X373647Y335000D01*
X374022Y335833D01*
X374272Y337000D01*
X374022Y338000D01*
X373522Y338667D01*
X372647Y339167D01*
X369272D01*
Y329167D01*
X373397D01*
X374272Y329834D01*
X374772Y330834D01*
X375022Y332000D01*
X374772Y333167D01*
X374022Y334167D01*
X373147Y334500D01*
X369272D01*
G01X378147Y329167D02*
Y339167D01*
X381147D01*
X382147Y338667D01*
X382897Y337500D01*
X383147Y336167D01*
X382897Y334834D01*
X382272Y333834D01*
X381147Y333333D01*
X378147D01*
G01X394897Y331167D02*
X395647Y330000D01*
X396647Y329334D01*
X397772Y329167D01*
X398772Y329334D01*
X399772Y330167D01*
X400397Y331167D01*
X400522Y332167D01*
X400272Y333333D01*
X399397Y334167D01*
X398522Y334500D01*
X397397D01*
G01X398522D02*
X399272Y335000D01*
X399897Y335833D01*
X400147Y336834D01*
X399897Y337834D01*
X399272Y338667D01*
X398147Y339167D01*
X397022Y339000D01*
X395897Y338334D01*
G01X327717Y514034D02*
Y504034D01*
G01X324842Y514034D02*
X330592D01*
G01X333717Y504034D02*
Y514034D01*
X336842D01*
X337842Y513534D01*
X338467Y512867D01*
X338717Y511534D01*
X338467Y510201D01*
X337717Y509367D01*
X336842Y508867D01*
X333717D01*
G01X336842D02*
X338717Y504034D01*
G01X341592D02*
X344717Y514034D01*
X347842Y504034D01*
G01X346717Y507534D02*
X342717D01*
G01X353217Y504034D02*
Y508534D01*
X350717Y514034D01*
G01X355717D02*
X353217Y508534D01*
G01X371217Y509367D02*
X371717Y509867D01*
X372092Y510700D01*
X372342Y511867D01*
X372092Y512867D01*
X371592Y513534D01*
X370717Y514034D01*
X367342D01*
Y504034D01*
X371467D01*
X372342Y504701D01*
X372842Y505701D01*
X373092Y506867D01*
X372842Y508034D01*
X372092Y509034D01*
X371217Y509367D01*
X367342D01*
G01X376217Y504034D02*
Y514034D01*
X379217D01*
X380217Y513534D01*
X380967Y512367D01*
X381217Y511034D01*
X380967Y509701D01*
X380342Y508701D01*
X379217Y508200D01*
X376217D01*
G01X397217Y504034D02*
Y514034D01*
X392592Y506867D01*
X398842D01*
G01X325787Y688129D02*
Y678129D01*
G01X322912Y688129D02*
X328662D01*
G01X331787Y678129D02*
Y688129D01*
X334912D01*
X335912Y687629D01*
X336537Y686962D01*
X336787Y685629D01*
X336537Y684296D01*
X335787Y683462D01*
X334912Y682962D01*
X331787D01*
G01X334912D02*
X336787Y678129D01*
G01X339662D02*
X342787Y688129D01*
X345912Y678129D01*
G01X344787Y681629D02*
X340787D01*
G01X351287Y678129D02*
Y682629D01*
X348787Y688129D01*
G01X353787D02*
X351287Y682629D01*
G01X369287Y683462D02*
X369787Y683962D01*
X370162Y684795D01*
X370412Y685962D01*
X370162Y686962D01*
X369662Y687629D01*
X368787Y688129D01*
X365412D01*
Y678129D01*
X369537D01*
X370412Y678796D01*
X370912Y679796D01*
X371162Y680962D01*
X370912Y682129D01*
X370162Y683129D01*
X369287Y683462D01*
X365412D01*
G01X374287Y678129D02*
Y688129D01*
X377287D01*
X378287Y687629D01*
X379037Y686462D01*
X379287Y685129D01*
X379037Y683796D01*
X378412Y682796D01*
X377287Y682295D01*
X374287D01*
G01X391037Y679629D02*
X391787Y678796D01*
X392662Y678296D01*
X393787Y678129D01*
X394912Y678462D01*
X395787Y679129D01*
X396412Y680296D01*
X396537Y681629D01*
X396287Y682962D01*
X395662Y683796D01*
X394787Y684462D01*
X393912Y684629D01*
X393037Y684462D01*
X391912Y683796D01*
X392287Y688129D01*
X395662D01*
G01X328103Y864925D02*
Y854925D01*
G01X325228Y864925D02*
X330978D01*
G01X334103Y854925D02*
Y864925D01*
X337228D01*
X338228Y864425D01*
X338853Y863758D01*
X339103Y862425D01*
X338853Y861092D01*
X338103Y860258D01*
X337228Y859758D01*
X334103D01*
G01X337228D02*
X339103Y854925D01*
G01X341978D02*
X345103Y864925D01*
X348228Y854925D01*
G01X347103Y858425D02*
X343103D01*
G01X353603Y854925D02*
Y859425D01*
X351103Y864925D01*
G01X356103D02*
X353603Y859425D01*
G01X371603Y860258D02*
X372103Y860758D01*
X372478Y861591D01*
X372728Y862758D01*
X372478Y863758D01*
X371978Y864425D01*
X371103Y864925D01*
X367728D01*
Y854925D01*
X371853D01*
X372728Y855592D01*
X373228Y856592D01*
X373478Y857758D01*
X373228Y858925D01*
X372478Y859925D01*
X371603Y860258D01*
X367728D01*
G01X376603Y854925D02*
Y864925D01*
X379603D01*
X380603Y864425D01*
X381353Y863258D01*
X381603Y861925D01*
X381353Y860592D01*
X380728Y859592D01*
X379603Y859091D01*
X376603D01*
G01X393728D02*
X394603Y860258D01*
X395353Y860925D01*
X396353Y861258D01*
X397228Y860925D01*
X397853Y860258D01*
X398353Y859258D01*
X398478Y858092D01*
X398353Y857092D01*
X397853Y856091D01*
X397103Y855258D01*
X396228Y854925D01*
X395228Y855258D01*
X394353Y856258D01*
X393853Y857758D01*
X393728Y859425D01*
X393978Y861591D01*
X394353Y862758D01*
X394978Y863925D01*
X395853Y864758D01*
X396728Y864925D01*
X397603Y864592D01*
X398228Y863758D01*
G01X327331Y1040949D02*
Y1030949D01*
G01X324456Y1040949D02*
X330206D01*
G01X333331Y1030949D02*
Y1040949D01*
X336456D01*
X337456Y1040449D01*
X338081Y1039782D01*
X338331Y1038449D01*
X338081Y1037116D01*
X337331Y1036282D01*
X336456Y1035782D01*
X333331D01*
G01X336456D02*
X338331Y1030949D01*
G01X341206D02*
X344331Y1040949D01*
X347456Y1030949D01*
G01X346331Y1034449D02*
X342331D01*
G01X352831Y1030949D02*
Y1035449D01*
X350331Y1040949D01*
G01X355331D02*
X352831Y1035449D01*
G01X370831Y1036282D02*
X371331Y1036782D01*
X371706Y1037615D01*
X371956Y1038782D01*
X371706Y1039782D01*
X371206Y1040449D01*
X370331Y1040949D01*
X366956D01*
Y1030949D01*
X371081D01*
X371956Y1031616D01*
X372456Y1032616D01*
X372706Y1033782D01*
X372456Y1034949D01*
X371706Y1035949D01*
X370831Y1036282D01*
X366956D01*
G01X375831Y1030949D02*
Y1040949D01*
X378831D01*
X379831Y1040449D01*
X380581Y1039282D01*
X380831Y1037949D01*
X380581Y1036616D01*
X379956Y1035616D01*
X378831Y1035115D01*
X375831D01*
G01X395081Y1030949D02*
X395331Y1033116D01*
X395706Y1034949D01*
X396206Y1036616D01*
X396831Y1038449D01*
X397831Y1040949D01*
X392831D01*
G01X328103Y1216973D02*
Y1206973D01*
G01X325228Y1216973D02*
X330978D01*
G01X334103Y1206973D02*
Y1216973D01*
X337228D01*
X338228Y1216473D01*
X338853Y1215806D01*
X339103Y1214473D01*
X338853Y1213140D01*
X338103Y1212306D01*
X337228Y1211806D01*
X334103D01*
G01X337228D02*
X339103Y1206973D01*
G01X341978D02*
X345103Y1216973D01*
X348228Y1206973D01*
G01X347103Y1210473D02*
X343103D01*
G01X353603Y1206973D02*
Y1211473D01*
X351103Y1216973D01*
G01X356103D02*
X353603Y1211473D01*
G01X371603Y1212306D02*
X372103Y1212806D01*
X372478Y1213639D01*
X372728Y1214806D01*
X372478Y1215806D01*
X371978Y1216473D01*
X371103Y1216973D01*
X367728D01*
Y1206973D01*
X371853D01*
X372728Y1207640D01*
X373228Y1208640D01*
X373478Y1209806D01*
X373228Y1210973D01*
X372478Y1211973D01*
X371603Y1212306D01*
X367728D01*
G01X376603Y1206973D02*
Y1216973D01*
X379603D01*
X380603Y1216473D01*
X381353Y1215306D01*
X381603Y1213973D01*
X381353Y1212640D01*
X380728Y1211640D01*
X379603Y1211139D01*
X376603D01*
G01X396103Y1206973D02*
X396978Y1207140D01*
X397978Y1207640D01*
X398603Y1208473D01*
X398853Y1209640D01*
X398603Y1210806D01*
X397853Y1211806D01*
X396728Y1212306D01*
X395478D01*
X394728Y1212640D01*
X394103Y1213473D01*
X393853Y1214640D01*
X394228Y1215806D01*
X395103Y1216640D01*
X396103Y1216973D01*
X397103Y1216640D01*
X397978Y1215806D01*
X398353Y1214640D01*
X398103Y1213473D01*
X397478Y1212640D01*
X396728Y1212306D01*
X395478D01*
X394353Y1211806D01*
X393603Y1210806D01*
X393353Y1209640D01*
X393603Y1208473D01*
X394228Y1207640D01*
X395228Y1207140D01*
X396103Y1206973D01*
G01X325015Y1389524D02*
Y1379524D01*
G01X322140Y1389524D02*
X327890D01*
G01X331015Y1379524D02*
Y1389524D01*
X334140D01*
X335140Y1389024D01*
X335765Y1388357D01*
X336015Y1387024D01*
X335765Y1385691D01*
X335015Y1384857D01*
X334140Y1384357D01*
X331015D01*
G01X334140D02*
X336015Y1379524D01*
G01X338890D02*
X342015Y1389524D01*
X345140Y1379524D01*
G01X344015Y1383024D02*
X340015D01*
G01X350515Y1379524D02*
Y1384024D01*
X348015Y1389524D01*
G01X353015D02*
X350515Y1384024D01*
G01X368515Y1384857D02*
X369015Y1385357D01*
X369390Y1386190D01*
X369640Y1387357D01*
X369390Y1388357D01*
X368890Y1389024D01*
X368015Y1389524D01*
X364640D01*
Y1379524D01*
X368765D01*
X369640Y1380191D01*
X370140Y1381191D01*
X370390Y1382357D01*
X370140Y1383524D01*
X369390Y1384524D01*
X368515Y1384857D01*
X364640D01*
G01X373515Y1379524D02*
Y1389524D01*
X376515D01*
X377515Y1389024D01*
X378265Y1387857D01*
X378515Y1386524D01*
X378265Y1385191D01*
X377640Y1384191D01*
X376515Y1383690D01*
X373515D01*
G01X390890Y1380690D02*
X391765Y1379857D01*
X392765Y1379524D01*
X393765Y1379857D01*
X394640Y1380857D01*
X395265Y1382357D01*
X395515Y1383857D01*
Y1385691D01*
X395265Y1387191D01*
X394640Y1388524D01*
X393890Y1389191D01*
X393015Y1389524D01*
X392015Y1389191D01*
X391265Y1388524D01*
X390765Y1387524D01*
X390515Y1386190D01*
X390765Y1385024D01*
X391390Y1383857D01*
X392140Y1383190D01*
X393015Y1383024D01*
X394015Y1383357D01*
X394765Y1384191D01*
X395515Y1385691D01*
G01X320768Y1909877D02*
Y1899877D01*
G01X317893Y1909877D02*
X323643D01*
G01X326768Y1899877D02*
Y1909877D01*
X329893D01*
X330893Y1909377D01*
X331518Y1908710D01*
X331768Y1907377D01*
X331518Y1906044D01*
X330768Y1905210D01*
X329893Y1904710D01*
X326768D01*
G01X329893D02*
X331768Y1899877D01*
G01X334643D02*
X337768Y1909877D01*
X340893Y1899877D01*
G01X339768Y1903377D02*
X335768D01*
G01X346268Y1899877D02*
Y1904377D01*
X343768Y1909877D01*
G01X348768D02*
X346268Y1904377D01*
G01X364268Y1905210D02*
X364768Y1905710D01*
X365143Y1906543D01*
X365393Y1907710D01*
X365143Y1908710D01*
X364643Y1909377D01*
X363768Y1909877D01*
X360393D01*
Y1899877D01*
X364518D01*
X365393Y1900544D01*
X365893Y1901544D01*
X366143Y1902710D01*
X365893Y1903877D01*
X365143Y1904877D01*
X364268Y1905210D01*
X360393D01*
G01X369268Y1899877D02*
Y1909877D01*
X372268D01*
X373268Y1909377D01*
X374018Y1908210D01*
X374268Y1906877D01*
X374018Y1905544D01*
X373393Y1904544D01*
X372268Y1904043D01*
X369268D01*
G01X388768Y1899877D02*
Y1909877D01*
X387268Y1907877D01*
G01Y1899877D02*
X390268D01*
G01X394893Y1908210D02*
X395643Y1909210D01*
X396518Y1909710D01*
X397518Y1909877D01*
X398768Y1909544D01*
X399643Y1908710D01*
X399893Y1907710D01*
X399768Y1906710D01*
X399268Y1905877D01*
X396768Y1904210D01*
X395643Y1903044D01*
X394893Y1901377D01*
X394643Y1899877D01*
X399893D01*
G54D11*
G01X-723776Y2987387D02*
Y-376795D01*
Y-489221D01*
X1782976D01*
Y-376795D01*
Y2987387D01*
X-723776D01*
G01X-4000Y-62500D02*
Y-137500D01*
X496000D01*
Y-62500D01*
X-4000D01*
G01X104331Y0D02*
X397638D01*
G03X405512Y7874I0J7874D01*
G01Y2078740D01*
G03X397638Y2086614I-7874J0D01*
G01X104331D01*
G03X98425Y2080709I0J-5906D01*
G01Y2076772D01*
G02X92520Y2070866I-5905J-1D01*
G01X5906D01*
G03X0Y2064961I-1J-5905D01*
G01Y21654D01*
G03X5906Y15748I5906J0D01*
G01X92520D01*
G02X98425Y9843I0J-5905D01*
G01Y5906D01*
G03X104331Y0I5906J0D01*
G01X8000Y-127500D02*
Y-132500D01*
G01X6543Y-127500D02*
X9457D01*
G01X14367Y-132500D02*
X11833D01*
Y-127500D01*
X14367D01*
G01X13353Y-129917D02*
X11833D01*
G01X16933Y-127500D02*
Y-132500D01*
X19467D01*
G01X23300Y-132667D02*
X23173Y-132583D01*
Y-132417D01*
X23300Y-132333D01*
X23427Y-132417D01*
Y-132583D01*
X23300Y-132667D01*
G01Y-130417D02*
X23173Y-130333D01*
Y-130167D01*
X23300Y-130083D01*
X23427Y-130167D01*
Y-130333D01*
X23300Y-130417D01*
G01X28083Y-134167D02*
X27450Y-133333D01*
X27133Y-132500D01*
Y-129167D01*
X27450Y-128333D01*
X28083Y-127500D01*
G01X33500D02*
X32993Y-127667D01*
X32613Y-128083D01*
X32360Y-128583D01*
X32170Y-129250D01*
X32107Y-130000D01*
X32170Y-130750D01*
X32360Y-131417D01*
X32613Y-131917D01*
X32993Y-132333D01*
X33500Y-132500D01*
X34007Y-132333D01*
X34387Y-131917D01*
X34640Y-131417D01*
X34830Y-130750D01*
X34893Y-130000D01*
X34830Y-129250D01*
X34640Y-128583D01*
X34387Y-128083D01*
X34007Y-127667D01*
X33500Y-127500D01*
G01X37207Y-131500D02*
X37587Y-132083D01*
X38093Y-132417D01*
X38663Y-132500D01*
X39170Y-132417D01*
X39677Y-132000D01*
X39993Y-131500D01*
X40057Y-131000D01*
X39930Y-130417D01*
X39487Y-130000D01*
X39043Y-129833D01*
X38473D01*
G01X39043D02*
X39423Y-129583D01*
X39740Y-129167D01*
X39867Y-128667D01*
X39740Y-128167D01*
X39423Y-127750D01*
X38853Y-127500D01*
X38283Y-127583D01*
X37713Y-127917D01*
G01X44017Y-134167D02*
X44650Y-133333D01*
X44967Y-132500D01*
Y-129167D01*
X44650Y-128333D01*
X44017Y-127500D01*
G01X47407Y-131500D02*
X47787Y-132083D01*
X48293Y-132417D01*
X48863Y-132500D01*
X49370Y-132417D01*
X49877Y-132000D01*
X50193Y-131500D01*
X50257Y-131000D01*
X50130Y-130417D01*
X49687Y-130000D01*
X49243Y-129833D01*
X48673D01*
G01X49243D02*
X49623Y-129583D01*
X49940Y-129167D01*
X50067Y-128667D01*
X49940Y-128167D01*
X49623Y-127750D01*
X49053Y-127500D01*
X48483Y-127583D01*
X47913Y-127917D01*
G01X52697Y-128333D02*
X53077Y-127833D01*
X53520Y-127583D01*
X54027Y-127500D01*
X54660Y-127667D01*
X55103Y-128083D01*
X55230Y-128583D01*
X55167Y-129083D01*
X54913Y-129500D01*
X53647Y-130333D01*
X53077Y-130917D01*
X52697Y-131750D01*
X52570Y-132500D01*
X55230D01*
G01X58873D02*
X59000Y-131417D01*
X59190Y-130500D01*
X59443Y-129667D01*
X59760Y-128750D01*
X60267Y-127500D01*
X57733D01*
G01X63277Y-130833D02*
X64923D01*
G01X67997Y-128333D02*
X68377Y-127833D01*
X68820Y-127583D01*
X69327Y-127500D01*
X69960Y-127667D01*
X70403Y-128083D01*
X70530Y-128583D01*
X70467Y-129083D01*
X70213Y-129500D01*
X68947Y-130333D01*
X68377Y-130917D01*
X67997Y-131750D01*
X67870Y-132500D01*
X70530D01*
G01X72907Y-131500D02*
X73287Y-132083D01*
X73793Y-132417D01*
X74363Y-132500D01*
X74870Y-132417D01*
X75377Y-132000D01*
X75693Y-131500D01*
X75757Y-131000D01*
X75630Y-130417D01*
X75187Y-130000D01*
X74743Y-129833D01*
X74173D01*
G01X74743D02*
X75123Y-129583D01*
X75440Y-129167D01*
X75567Y-128667D01*
X75440Y-128167D01*
X75123Y-127750D01*
X74553Y-127500D01*
X73983Y-127583D01*
X73413Y-127917D01*
G01X80160Y-132500D02*
Y-127500D01*
X77817Y-131083D01*
X80983D01*
G01X83107Y-131750D02*
X83487Y-132167D01*
X83930Y-132417D01*
X84500Y-132500D01*
X85070Y-132333D01*
X85513Y-132000D01*
X85830Y-131417D01*
X85893Y-130750D01*
X85767Y-130083D01*
X85450Y-129667D01*
X85007Y-129333D01*
X84563Y-129250D01*
X84120Y-129333D01*
X83550Y-129667D01*
X83740Y-127500D01*
X85450D01*
G01X93497Y-132500D02*
Y-127500D01*
X95903D01*
G01X95017Y-129917D02*
X93497D01*
G01X98217Y-132500D02*
X99800Y-127500D01*
X101383Y-132500D01*
G01X100813Y-130750D02*
X98787D01*
G01X103570Y-132500D02*
X106230Y-127500D01*
G01X103570D02*
X106230Y-132500D01*
G01X110000Y-132667D02*
X109873Y-132583D01*
Y-132417D01*
X110000Y-132333D01*
X110127Y-132417D01*
Y-132583D01*
X110000Y-132667D01*
G01Y-130417D02*
X109873Y-130333D01*
Y-130167D01*
X110000Y-130083D01*
X110127Y-130167D01*
Y-130333D01*
X110000Y-130417D01*
G01X114783Y-134167D02*
X114150Y-133333D01*
X113833Y-132500D01*
Y-129167D01*
X114150Y-128333D01*
X114783Y-127500D01*
G01X120200D02*
X119693Y-127667D01*
X119313Y-128083D01*
X119060Y-128583D01*
X118870Y-129250D01*
X118807Y-130000D01*
X118870Y-130750D01*
X119060Y-131417D01*
X119313Y-131917D01*
X119693Y-132333D01*
X120200Y-132500D01*
X120707Y-132333D01*
X121087Y-131917D01*
X121340Y-131417D01*
X121530Y-130750D01*
X121593Y-130000D01*
X121530Y-129250D01*
X121340Y-128583D01*
X121087Y-128083D01*
X120707Y-127667D01*
X120200Y-127500D01*
G01X123907Y-131500D02*
X124287Y-132083D01*
X124793Y-132417D01*
X125363Y-132500D01*
X125870Y-132417D01*
X126377Y-132000D01*
X126693Y-131500D01*
X126757Y-131000D01*
X126630Y-130417D01*
X126187Y-130000D01*
X125743Y-129833D01*
X125173D01*
G01X125743D02*
X126123Y-129583D01*
X126440Y-129167D01*
X126567Y-128667D01*
X126440Y-128167D01*
X126123Y-127750D01*
X125553Y-127500D01*
X124983Y-127583D01*
X124413Y-127917D01*
G01X130717Y-134167D02*
X131350Y-133333D01*
X131667Y-132500D01*
Y-129167D01*
X131350Y-128333D01*
X130717Y-127500D01*
G01X134107Y-131500D02*
X134487Y-132083D01*
X134993Y-132417D01*
X135563Y-132500D01*
X136070Y-132417D01*
X136577Y-132000D01*
X136893Y-131500D01*
X136957Y-131000D01*
X136830Y-130417D01*
X136387Y-130000D01*
X135943Y-129833D01*
X135373D01*
G01X135943D02*
X136323Y-129583D01*
X136640Y-129167D01*
X136767Y-128667D01*
X136640Y-128167D01*
X136323Y-127750D01*
X135753Y-127500D01*
X135183Y-127583D01*
X134613Y-127917D01*
G01X139523Y-131917D02*
X139967Y-132333D01*
X140473Y-132500D01*
X140980Y-132333D01*
X141423Y-131833D01*
X141740Y-131083D01*
X141867Y-130333D01*
Y-129417D01*
X141740Y-128667D01*
X141423Y-128000D01*
X141043Y-127667D01*
X140600Y-127500D01*
X140093Y-127667D01*
X139713Y-128000D01*
X139460Y-128500D01*
X139333Y-129167D01*
X139460Y-129750D01*
X139777Y-130333D01*
X140157Y-130667D01*
X140600Y-130750D01*
X141107Y-130583D01*
X141487Y-130167D01*
X141867Y-129417D01*
G01X145573Y-132500D02*
X145700Y-131417D01*
X145890Y-130500D01*
X146143Y-129667D01*
X146460Y-128750D01*
X146967Y-127500D01*
X144433D01*
G01X149977Y-130833D02*
X151623D01*
G01X154507Y-131500D02*
X154887Y-132083D01*
X155393Y-132417D01*
X155963Y-132500D01*
X156470Y-132417D01*
X156977Y-132000D01*
X157293Y-131500D01*
X157357Y-131000D01*
X157230Y-130417D01*
X156787Y-130000D01*
X156343Y-129833D01*
X155773D01*
G01X156343D02*
X156723Y-129583D01*
X157040Y-129167D01*
X157167Y-128667D01*
X157040Y-128167D01*
X156723Y-127750D01*
X156153Y-127500D01*
X155583Y-127583D01*
X155013Y-127917D01*
G01X159797Y-130417D02*
X160240Y-129833D01*
X160620Y-129500D01*
X161127Y-129333D01*
X161570Y-129500D01*
X161887Y-129833D01*
X162140Y-130333D01*
X162203Y-130917D01*
X162140Y-131417D01*
X161887Y-131917D01*
X161507Y-132333D01*
X161063Y-132500D01*
X160557Y-132333D01*
X160113Y-131833D01*
X159860Y-131083D01*
X159797Y-130250D01*
X159923Y-129167D01*
X160113Y-128583D01*
X160430Y-128000D01*
X160873Y-127583D01*
X161317Y-127500D01*
X161760Y-127667D01*
X162077Y-128083D01*
G01X166100Y-132500D02*
Y-127500D01*
X165340Y-128500D01*
G01Y-132500D02*
X166860D01*
G01X171960D02*
Y-127500D01*
X169617Y-131083D01*
X172783D01*
G01X191000Y-62500D02*
Y-137500D01*
G01Y-112500D02*
X294000D01*
Y-87500D01*
G01X191000D02*
X294000D01*
G01X301507Y-122500D02*
Y-117500D01*
X302773D01*
X303280Y-117750D01*
X303660Y-118083D01*
X303977Y-118583D01*
X304230Y-119167D01*
X304293Y-120000D01*
X304230Y-120833D01*
X303977Y-121417D01*
X303660Y-121917D01*
X303280Y-122250D01*
X302773Y-122500D01*
X301507D01*
G01X306417D02*
X308000Y-117500D01*
X309583Y-122500D01*
G01X309013Y-120750D02*
X306987D01*
G01X313100Y-117500D02*
Y-122500D01*
G01X311643Y-117500D02*
X314557D01*
G01X319467Y-122500D02*
X316933D01*
Y-117500D01*
X319467D01*
G01X318453Y-119917D02*
X316933D01*
G01X323300Y-122667D02*
X323173Y-122583D01*
Y-122417D01*
X323300Y-122333D01*
X323427Y-122417D01*
Y-122583D01*
X323300Y-122667D01*
G01Y-120417D02*
X323173Y-120333D01*
Y-120167D01*
X323300Y-120083D01*
X323427Y-120167D01*
Y-120333D01*
X323300Y-120417D01*
G01X296000Y-62500D02*
Y-137500D01*
G01X294000Y-62500D02*
Y-137500D01*
G01X301633Y-97500D02*
Y-92500D01*
X303153D01*
X303660Y-92750D01*
X304040Y-93333D01*
X304167Y-94000D01*
X304040Y-94667D01*
X303723Y-95167D01*
X303153Y-95417D01*
X301633D01*
G01X306860Y-97667D02*
X309140Y-92500D01*
G01X311643Y-97500D02*
Y-92500D01*
X314557Y-97500D01*
Y-92500D01*
G01X318200Y-97667D02*
X318073Y-97583D01*
Y-97417D01*
X318200Y-97333D01*
X318327Y-97417D01*
Y-97583D01*
X318200Y-97667D01*
G01Y-95417D02*
X318073Y-95333D01*
Y-95167D01*
X318200Y-95083D01*
X318327Y-95167D01*
Y-95333D01*
X318200Y-95417D01*
G01X296000Y-112500D02*
X496000D01*
G01X301633Y-72500D02*
Y-67500D01*
X303153D01*
X303660Y-67750D01*
X304040Y-68333D01*
X304167Y-69000D01*
X304040Y-69667D01*
X303723Y-70167D01*
X303153Y-70417D01*
X301633D01*
G01X306733Y-72500D02*
Y-67500D01*
X308317D01*
X308823Y-67750D01*
X309140Y-68083D01*
X309267Y-68750D01*
X309140Y-69417D01*
X308760Y-69833D01*
X308317Y-70083D01*
X306733D01*
G01X308317D02*
X309267Y-72500D01*
G01X313100D02*
X312593Y-72417D01*
X312150Y-72083D01*
X311770Y-71583D01*
X311517Y-71000D01*
X311390Y-70333D01*
Y-69667D01*
X311517Y-69000D01*
X311770Y-68417D01*
X312150Y-67917D01*
X312593Y-67583D01*
X313100Y-67500D01*
X313607Y-67583D01*
X314050Y-67917D01*
X314430Y-68417D01*
X314683Y-69000D01*
X314810Y-69667D01*
Y-70333D01*
X314683Y-71000D01*
X314430Y-71583D01*
X314050Y-72083D01*
X313607Y-72417D01*
X313100Y-72500D01*
G01X316933Y-71500D02*
X317250Y-72000D01*
X317630Y-72333D01*
X318073Y-72500D01*
X318580Y-72333D01*
X318960Y-72000D01*
X319340Y-71500D01*
X319467Y-70833D01*
Y-67500D01*
G01X324567Y-72500D02*
X322033D01*
Y-67500D01*
X324567D01*
G01X323553Y-69917D02*
X322033D01*
G01X329793Y-67917D02*
X329413Y-67667D01*
X328970Y-67500D01*
X328463D01*
X327893Y-67750D01*
X327450Y-68167D01*
X327133Y-68667D01*
X326880Y-69500D01*
X326817Y-70250D01*
X326943Y-71000D01*
X327133Y-71500D01*
X327513Y-72000D01*
X327957Y-72333D01*
X328400Y-72500D01*
X328843D01*
X329287Y-72333D01*
X329667Y-72083D01*
X329983Y-71750D01*
G01X333500Y-67500D02*
Y-72500D01*
G01X332043Y-67500D02*
X334957D01*
G01X338600Y-72667D02*
X338473Y-72583D01*
Y-72417D01*
X338600Y-72333D01*
X338727Y-72417D01*
Y-72583D01*
X338600Y-72667D01*
G01Y-70417D02*
X338473Y-70333D01*
Y-70167D01*
X338600Y-70083D01*
X338727Y-70167D01*
Y-70333D01*
X338600Y-70417D01*
G01X296000Y-87500D02*
X496000D01*
G01X317323Y1885039D02*
Y1881102D01*
G02X296850I-10237J0D01*
G01Y1885039D01*
G02X317323I10236J0D01*
G01X411000Y-112500D02*
Y-137500D01*
G01X416633Y-122500D02*
Y-117500D01*
X418217D01*
X418723Y-117750D01*
X419040Y-118083D01*
X419167Y-118750D01*
X419040Y-119417D01*
X418660Y-119833D01*
X418217Y-120083D01*
X416633D01*
G01X418217D02*
X419167Y-122500D01*
G01X424267D02*
X421733D01*
Y-117500D01*
X424267D01*
G01X423253Y-119917D02*
X421733D01*
G01X426517Y-117500D02*
X428100Y-122500D01*
X429683Y-117500D01*
G01X433200Y-122667D02*
X433073Y-122583D01*
Y-122417D01*
X433200Y-122333D01*
X433327Y-122417D01*
Y-122583D01*
X433200Y-122667D01*
G01Y-120417D02*
X433073Y-120333D01*
Y-120167D01*
X433200Y-120083D01*
X433327Y-120167D01*
Y-120333D01*
X433200Y-120417D01*
G01X460000Y-112500D02*
Y-137500D01*
G01X-723776Y2987387D02*
Y-376795D01*
Y-489221D01*
X1782976D01*
Y-376795D01*
Y2987387D01*
X-723776D01*
G01X47633Y1053821D02*
X-11619D01*
Y678900D01*
X47633D01*
Y1053821D01*
G01X16471Y690711D02*
X192D01*
Y1042010D01*
X35822D01*
G01X47637Y1412086D02*
X-11615D01*
Y1037165D01*
X47637D01*
Y1412086D01*
G01X16475Y1048976D02*
X196D01*
Y1400275D01*
X35826D01*
G01X6705Y-124160D02*
X7332Y-124685D01*
X8037Y-125000D01*
X8663D01*
X9290Y-124685D01*
X9760Y-124160D01*
X9995Y-123425D01*
X9838Y-122690D01*
X9447Y-122060D01*
X8742Y-121640D01*
X7802Y-121430D01*
X7253Y-121010D01*
X7018Y-120275D01*
X7175Y-119540D01*
X7567Y-119015D01*
X8115Y-118700D01*
X8663D01*
X9212Y-118910D01*
X9682Y-119435D01*
G01X13005Y-125000D02*
Y-118700D01*
G01X16295D02*
Y-125000D01*
G01Y-121850D02*
X13005D01*
G01X20010Y-118700D02*
X21890D01*
G01X20950D02*
Y-125000D01*
G01X20010D02*
X21890D01*
G01X28817D02*
X25683D01*
Y-118700D01*
X28817D01*
G01X27563Y-121745D02*
X25683D01*
G01X31748Y-125000D02*
Y-118700D01*
X35352Y-125000D01*
Y-118700D01*
G01X39693Y-126155D02*
X40007Y-124790D01*
G01X46150Y-118700D02*
Y-125000D01*
G01X44348Y-118700D02*
X47952D01*
G01X50492Y-125000D02*
X52450Y-118700D01*
X54408Y-125000D01*
G01X53703Y-122795D02*
X51197D01*
G01X57810Y-118700D02*
X59690D01*
G01X58750D02*
Y-125000D01*
G01X57810D02*
X59690D01*
G01X62700Y-118700D02*
X63797Y-125000D01*
X65050Y-118700D01*
X66303Y-125000D01*
X67400Y-118700D01*
G01X69392Y-125000D02*
X71350Y-118700D01*
X73308Y-125000D01*
G01X72603Y-122795D02*
X70097D01*
G01X75848Y-125000D02*
Y-118700D01*
X79452Y-125000D01*
Y-118700D01*
G01X88683Y-125000D02*
Y-118700D01*
X90642D01*
X91268Y-119015D01*
X91660Y-119435D01*
X91817Y-120275D01*
X91660Y-121115D01*
X91190Y-121640D01*
X90642Y-121955D01*
X88683D01*
G01X90642D02*
X91817Y-125000D01*
G01X96550Y-125210D02*
X96393Y-125105D01*
Y-124895D01*
X96550Y-124790D01*
X96707Y-124895D01*
Y-125105D01*
X96550Y-125210D01*
G01X102850Y-125000D02*
X102223Y-124895D01*
X101675Y-124475D01*
X101205Y-123845D01*
X100892Y-123110D01*
X100735Y-122270D01*
Y-121430D01*
X100892Y-120590D01*
X101205Y-119855D01*
X101675Y-119225D01*
X102223Y-118805D01*
X102850Y-118700D01*
X103477Y-118805D01*
X104025Y-119225D01*
X104495Y-119855D01*
X104808Y-120590D01*
X104965Y-121430D01*
Y-122270D01*
X104808Y-123110D01*
X104495Y-123845D01*
X104025Y-124475D01*
X103477Y-124895D01*
X102850Y-125000D01*
G01X109150Y-125210D02*
X108993Y-125105D01*
Y-124895D01*
X109150Y-124790D01*
X109307Y-124895D01*
Y-125105D01*
X109150Y-125210D01*
G01X117173Y-119225D02*
X116703Y-118910D01*
X116155Y-118700D01*
X115528D01*
X114823Y-119015D01*
X114275Y-119540D01*
X113883Y-120170D01*
X113570Y-121220D01*
X113492Y-122165D01*
X113648Y-123110D01*
X113883Y-123740D01*
X114353Y-124370D01*
X114902Y-124790D01*
X115450Y-125000D01*
X115998D01*
X116547Y-124790D01*
X117017Y-124475D01*
X117408Y-124055D01*
G01X121750Y-125210D02*
X121593Y-125105D01*
Y-124895D01*
X121750Y-124790D01*
X121907Y-124895D01*
Y-125105D01*
X121750Y-125210D01*
G01X6627Y-115000D02*
Y-108700D01*
G01X9603D02*
X6627Y-112585D01*
G01X10073Y-115000D02*
X7958Y-110800D01*
G01X12927Y-108700D02*
Y-113215D01*
X13240Y-114160D01*
X13867Y-114790D01*
X14650Y-115000D01*
X15433Y-114790D01*
X16060Y-114160D01*
X16373Y-113215D01*
Y-108700D01*
G01X22517Y-115000D02*
X19383D01*
Y-108700D01*
X22517D01*
G01X21263Y-111745D02*
X19383D01*
G01X26310Y-108700D02*
X28190D01*
G01X27250D02*
Y-115000D01*
G01X26310D02*
X28190D01*
G01X38205Y-114160D02*
X38832Y-114685D01*
X39537Y-115000D01*
X40163D01*
X40790Y-114685D01*
X41260Y-114160D01*
X41495Y-113425D01*
X41338Y-112690D01*
X40947Y-112060D01*
X40242Y-111640D01*
X39302Y-111430D01*
X38753Y-111010D01*
X38518Y-110275D01*
X38675Y-109540D01*
X39067Y-109015D01*
X39615Y-108700D01*
X40163D01*
X40712Y-108910D01*
X41182Y-109435D01*
G01X44505Y-115000D02*
Y-108700D01*
G01X47795D02*
Y-115000D01*
G01Y-111850D02*
X44505D01*
G01X50492Y-115000D02*
X52450Y-108700D01*
X54408Y-115000D01*
G01X53703Y-112795D02*
X51197D01*
G01X56948Y-115000D02*
Y-108700D01*
X60552Y-115000D01*
Y-108700D01*
G01X69705Y-115000D02*
Y-108700D01*
G01X72995D02*
Y-115000D01*
G01Y-111850D02*
X69705D01*
G01X76005Y-114160D02*
X76632Y-114685D01*
X77337Y-115000D01*
X77963D01*
X78590Y-114685D01*
X79060Y-114160D01*
X79295Y-113425D01*
X79138Y-112690D01*
X78747Y-112060D01*
X78042Y-111640D01*
X77102Y-111430D01*
X76553Y-111010D01*
X76318Y-110275D01*
X76475Y-109540D01*
X76867Y-109015D01*
X77415Y-108700D01*
X77963D01*
X78512Y-108910D01*
X78982Y-109435D01*
G01X83010Y-108700D02*
X84890D01*
G01X83950D02*
Y-115000D01*
G01X83010D02*
X84890D01*
G01X88292D02*
X90250Y-108700D01*
X92208Y-115000D01*
G01X91503Y-112795D02*
X88997D01*
G01X94748Y-115000D02*
Y-108700D01*
X98352Y-115000D01*
Y-108700D01*
G01X103320Y-111850D02*
X104887D01*
Y-113740D01*
X104417Y-114370D01*
X103868Y-114790D01*
X103085Y-115000D01*
X102302Y-114790D01*
X101753Y-114370D01*
X101283Y-113740D01*
X100970Y-113005D01*
X100813Y-112165D01*
Y-111430D01*
X100970Y-110800D01*
X101283Y-110065D01*
X101753Y-109435D01*
X102223Y-109015D01*
X102850Y-108700D01*
X103398D01*
X104025Y-108910D01*
X104495Y-109330D01*
G01X108993Y-116155D02*
X109307Y-114790D01*
G01X115450Y-108700D02*
Y-115000D01*
G01X113648Y-108700D02*
X117252D01*
G01X119792Y-115000D02*
X121750Y-108700D01*
X123708Y-115000D01*
G01X123003Y-112795D02*
X120497D01*
G01X128050Y-115000D02*
X127423Y-114895D01*
X126875Y-114475D01*
X126405Y-113845D01*
X126092Y-113110D01*
X125935Y-112270D01*
Y-111430D01*
X126092Y-110590D01*
X126405Y-109855D01*
X126875Y-109225D01*
X127423Y-108805D01*
X128050Y-108700D01*
X128677Y-108805D01*
X129225Y-109225D01*
X129695Y-109855D01*
X130008Y-110590D01*
X130165Y-111430D01*
Y-112270D01*
X130008Y-113110D01*
X129695Y-113845D01*
X129225Y-114475D01*
X128677Y-114895D01*
X128050Y-115000D01*
G01X140650D02*
Y-112165D01*
X139083Y-108700D01*
G01X142217D02*
X140650Y-112165D01*
G01X145227Y-108700D02*
Y-113215D01*
X145540Y-114160D01*
X146167Y-114790D01*
X146950Y-115000D01*
X147733Y-114790D01*
X148360Y-114160D01*
X148673Y-113215D01*
Y-108700D01*
G01X151292Y-115000D02*
X153250Y-108700D01*
X155208Y-115000D01*
G01X154503Y-112795D02*
X151997D01*
G01X157748Y-115000D02*
Y-108700D01*
X161352Y-115000D01*
Y-108700D01*
G01X30650Y-92300D02*
X28130Y-91883D01*
X25925Y-90217D01*
X24035Y-87717D01*
X22775Y-84800D01*
X22145Y-81467D01*
Y-78133D01*
X22775Y-74800D01*
X24035Y-71883D01*
X25925Y-69384D01*
X28130Y-67717D01*
X30650Y-67300D01*
X33170Y-67717D01*
X35375Y-69384D01*
X37265Y-71883D01*
X38525Y-74800D01*
X39155Y-78133D01*
Y-81467D01*
X38525Y-84800D01*
X37265Y-87717D01*
X35375Y-90217D01*
X33170Y-91883D01*
X30650Y-92300D01*
G01X33170Y-85633D02*
X36950Y-92300D01*
G01X50495Y-75634D02*
Y-87300D01*
X51755Y-90217D01*
X53645Y-91883D01*
X55850Y-92300D01*
X58055Y-91883D01*
X59945Y-90217D01*
X61205Y-87300D01*
G01Y-92300D02*
Y-75634D01*
G01X86720Y-92300D02*
Y-75634D01*
G01Y-78550D02*
X85460Y-76884D01*
X83570Y-76050D01*
X81365Y-75634D01*
X79160Y-76467D01*
X77270Y-78133D01*
X76010Y-80634D01*
X75380Y-83967D01*
X76010Y-87300D01*
X77270Y-89801D01*
X79160Y-91467D01*
X81365Y-92300D01*
X83570Y-91883D01*
X85460Y-90634D01*
X86720Y-88967D01*
G01X100895Y-92300D02*
Y-75634D01*
G01Y-79800D02*
X102155Y-77717D01*
X104045Y-76050D01*
X106565Y-75634D01*
X108770Y-76050D01*
X110660Y-77717D01*
X111605Y-80634D01*
Y-92300D01*
G01X131450Y-67300D02*
Y-92300D01*
G01X127040Y-75634D02*
X135860D01*
G01X162320Y-92300D02*
Y-75634D01*
G01Y-78550D02*
X161060Y-76884D01*
X159170Y-76050D01*
X156965Y-75634D01*
X154760Y-76467D01*
X152870Y-78133D01*
X151610Y-80634D01*
X150980Y-83967D01*
X151610Y-87300D01*
X152870Y-89801D01*
X154760Y-91467D01*
X156965Y-92300D01*
X159170Y-91883D01*
X161060Y-90634D01*
X162320Y-88967D01*
G01X6548Y-105000D02*
Y-98700D01*
X10152Y-105000D01*
Y-98700D01*
G01X14650Y-105000D02*
X14023Y-104895D01*
X13475Y-104475D01*
X13005Y-103845D01*
X12692Y-103110D01*
X12535Y-102270D01*
Y-101430D01*
X12692Y-100590D01*
X13005Y-99855D01*
X13475Y-99225D01*
X14023Y-98805D01*
X14650Y-98700D01*
X15277Y-98805D01*
X15825Y-99225D01*
X16295Y-99855D01*
X16608Y-100590D01*
X16765Y-101430D01*
Y-102270D01*
X16608Y-103110D01*
X16295Y-103845D01*
X15825Y-104475D01*
X15277Y-104895D01*
X14650Y-105000D01*
G01X20950Y-105210D02*
X20793Y-105105D01*
Y-104895D01*
X20950Y-104790D01*
X21107Y-104895D01*
Y-105105D01*
X20950Y-105210D01*
G01X27250Y-105000D02*
Y-98700D01*
X26310Y-99960D01*
G01Y-105000D02*
X28190D01*
G01X33550D02*
X34098Y-104895D01*
X34725Y-104580D01*
X35117Y-104055D01*
X35273Y-103320D01*
X35117Y-102585D01*
X34647Y-101955D01*
X33942Y-101640D01*
X33158D01*
X32688Y-101430D01*
X32297Y-100905D01*
X32140Y-100170D01*
X32375Y-99435D01*
X32923Y-98910D01*
X33550Y-98700D01*
X34177Y-98910D01*
X34725Y-99435D01*
X34960Y-100170D01*
X34803Y-100905D01*
X34412Y-101430D01*
X33942Y-101640D01*
X33158D01*
X32453Y-101955D01*
X31983Y-102585D01*
X31827Y-103320D01*
X31983Y-104055D01*
X32375Y-104580D01*
X33002Y-104895D01*
X33550Y-105000D01*
G01X39850D02*
X40398Y-104895D01*
X41025Y-104580D01*
X41417Y-104055D01*
X41573Y-103320D01*
X41417Y-102585D01*
X40947Y-101955D01*
X40242Y-101640D01*
X39458D01*
X38988Y-101430D01*
X38597Y-100905D01*
X38440Y-100170D01*
X38675Y-99435D01*
X39223Y-98910D01*
X39850Y-98700D01*
X40477Y-98910D01*
X41025Y-99435D01*
X41260Y-100170D01*
X41103Y-100905D01*
X40712Y-101430D01*
X40242Y-101640D01*
X39458D01*
X38753Y-101955D01*
X38283Y-102585D01*
X38127Y-103320D01*
X38283Y-104055D01*
X38675Y-104580D01*
X39302Y-104895D01*
X39850Y-105000D01*
G01X45993Y-106155D02*
X46307Y-104790D01*
G01X50100Y-98700D02*
X51197Y-105000D01*
X52450Y-98700D01*
X53703Y-105000D01*
X54800Y-98700D01*
G01X60317Y-105000D02*
X57183D01*
Y-98700D01*
X60317D01*
G01X59063Y-101745D02*
X57183D01*
G01X63248Y-105000D02*
Y-98700D01*
X66852Y-105000D01*
Y-98700D01*
G01X76005Y-105000D02*
Y-98700D01*
G01X79295D02*
Y-105000D01*
G01Y-101850D02*
X76005D01*
G01X81600Y-98700D02*
X82697Y-105000D01*
X83950Y-98700D01*
X85203Y-105000D01*
X86300Y-98700D01*
G01X88292Y-105000D02*
X90250Y-98700D01*
X92208Y-105000D01*
G01X91503Y-102795D02*
X88997D01*
G01X101362Y-99750D02*
X101832Y-99120D01*
X102380Y-98805D01*
X103007Y-98700D01*
X103790Y-98910D01*
X104338Y-99435D01*
X104495Y-100065D01*
X104417Y-100695D01*
X104103Y-101220D01*
X102537Y-102270D01*
X101832Y-103005D01*
X101362Y-104055D01*
X101205Y-105000D01*
X104495D01*
G01X107348D02*
Y-98700D01*
X110952Y-105000D01*
Y-98700D01*
G01X113727Y-105000D02*
Y-98700D01*
X115293D01*
X115920Y-99015D01*
X116390Y-99435D01*
X116782Y-100065D01*
X117095Y-100800D01*
X117173Y-101850D01*
X117095Y-102900D01*
X116782Y-103635D01*
X116390Y-104265D01*
X115920Y-104685D01*
X115293Y-105000D01*
X113727D01*
G01X126483D02*
Y-98700D01*
X128442D01*
X129068Y-99015D01*
X129460Y-99435D01*
X129617Y-100275D01*
X129460Y-101115D01*
X128990Y-101640D01*
X128442Y-101955D01*
X126483D01*
G01X128442D02*
X129617Y-105000D01*
G01X132627D02*
Y-98700D01*
X134193D01*
X134820Y-99015D01*
X135290Y-99435D01*
X135682Y-100065D01*
X135995Y-100800D01*
X136073Y-101850D01*
X135995Y-102900D01*
X135682Y-103635D01*
X135290Y-104265D01*
X134820Y-104685D01*
X134193Y-105000D01*
X132627D01*
G01X140650Y-105210D02*
X140493Y-105105D01*
Y-104895D01*
X140650Y-104790D01*
X140807Y-104895D01*
Y-105105D01*
X140650Y-105210D01*
G01X2435Y24839D02*
X2703Y24891D01*
X3010Y25046D01*
X3202Y25304D01*
X3278Y25666D01*
X3202Y26027D01*
X2972Y26337D01*
X2627Y26492D01*
X2243D01*
X2013Y26596D01*
X1822Y26854D01*
X1745Y27216D01*
X1860Y27577D01*
X2128Y27836D01*
X2435Y27939D01*
X2742Y27836D01*
X3010Y27577D01*
X3125Y27216D01*
X3048Y26854D01*
X2857Y26596D01*
X2627Y26492D01*
X2243D01*
X1898Y26337D01*
X1668Y26027D01*
X1592Y25666D01*
X1668Y25304D01*
X1860Y25046D01*
X2167Y24891D01*
X2435Y24839D01*
G01X4467Y85465D02*
X66003D01*
Y19953D01*
X4467D01*
Y85465D01*
G01X2358Y34539D02*
X2435Y35211D01*
X2550Y35779D01*
X2703Y36296D01*
X2895Y36864D01*
X3202Y37639D01*
X1668D01*
G01X66003Y156464D02*
X4467D01*
Y221976D01*
X66003D01*
Y156464D01*
G01X4268Y223963D02*
X4460Y223653D01*
X4690Y223446D01*
X4958Y223343D01*
X5265Y223446D01*
X5495Y223653D01*
X5725Y223963D01*
X5802Y224376D01*
Y226443D01*
G01X7407Y225926D02*
X7637Y226236D01*
X7905Y226391D01*
X8212Y226443D01*
X8595Y226340D01*
X8863Y226081D01*
X8940Y225771D01*
X8902Y225461D01*
X8748Y225203D01*
X7982Y224686D01*
X7637Y224325D01*
X7407Y223808D01*
X7330Y223343D01*
X8940D01*
G01X11235D02*
Y226443D01*
X10775Y225823D01*
G01Y223343D02*
X11695D01*
G01X1407Y217726D02*
X1637Y218036D01*
X1905Y218191D01*
X2212Y218243D01*
X2595Y218140D01*
X2863Y217881D01*
X2940Y217571D01*
X2902Y217261D01*
X2748Y217003D01*
X1982Y216486D01*
X1637Y216125D01*
X1407Y215608D01*
X1330Y215143D01*
X2940D01*
G01X2335Y209243D02*
Y212343D01*
X1875Y211723D01*
G01Y209243D02*
X2795D01*
G01X2698Y233170D02*
X2966Y233222D01*
X3273Y233377D01*
X3465Y233635D01*
X3541Y233997D01*
X3465Y234358D01*
X3235Y234668D01*
X2890Y234823D01*
X2506D01*
X2276Y234927D01*
X2085Y235185D01*
X2008Y235547D01*
X2123Y235908D01*
X2391Y236167D01*
X2698Y236270D01*
X3005Y236167D01*
X3273Y235908D01*
X3388Y235547D01*
X3311Y235185D01*
X3120Y234927D01*
X2890Y234823D01*
X2506D01*
X2161Y234668D01*
X1931Y234358D01*
X1855Y233997D01*
X1931Y233635D01*
X2123Y233377D01*
X2430Y233222D01*
X2698Y233170D01*
G01X2621Y242870D02*
X2698Y243542D01*
X2813Y244110D01*
X2966Y244627D01*
X3158Y245195D01*
X3465Y245970D01*
X1931D01*
G01X4467Y294323D02*
X66003D01*
Y228811D01*
X4467D01*
Y294323D01*
G01X66003Y365322D02*
X4467D01*
Y430834D01*
X66003D01*
Y365322D01*
G01X2335Y418101D02*
Y421201D01*
X1875Y420581D01*
G01Y418101D02*
X2795D01*
G01X4268Y432821D02*
X4460Y432511D01*
X4690Y432304D01*
X4958Y432201D01*
X5265Y432304D01*
X5495Y432511D01*
X5725Y432821D01*
X5802Y433234D01*
Y435301D01*
G01X7407Y434784D02*
X7637Y435094D01*
X7905Y435249D01*
X8212Y435301D01*
X8595Y435198D01*
X8863Y434939D01*
X8940Y434629D01*
X8902Y434319D01*
X8748Y434061D01*
X7982Y433544D01*
X7637Y433183D01*
X7407Y432666D01*
X7330Y432201D01*
X8940D01*
G01X11158D02*
X11235Y432873D01*
X11350Y433441D01*
X11503Y433958D01*
X11695Y434526D01*
X12002Y435301D01*
X10468D01*
G01X1407Y426584D02*
X1637Y426894D01*
X1905Y427049D01*
X2212Y427101D01*
X2595Y426998D01*
X2863Y426739D01*
X2940Y426429D01*
X2902Y426119D01*
X2748Y425861D01*
X1982Y425344D01*
X1637Y424983D01*
X1407Y424466D01*
X1330Y424001D01*
X2940D01*
G01X2611Y505997D02*
X2879Y506049D01*
X3186Y506204D01*
X3378Y506462D01*
X3454Y506824D01*
X3378Y507185D01*
X3148Y507495D01*
X2803Y507650D01*
X2419D01*
X2189Y507754D01*
X1998Y508012D01*
X1921Y508374D01*
X2036Y508735D01*
X2304Y508994D01*
X2611Y509097D01*
X2918Y508994D01*
X3186Y508735D01*
X3301Y508374D01*
X3224Y508012D01*
X3033Y507754D01*
X2803Y507650D01*
X2419D01*
X2074Y507495D01*
X1844Y507185D01*
X1768Y506824D01*
X1844Y506462D01*
X2036Y506204D01*
X2343Y506049D01*
X2611Y505997D01*
G01X68778Y523501D02*
Y503740D01*
X4212D01*
Y523501D01*
G01X2139Y516917D02*
X2216Y517589D01*
X2331Y518157D01*
X2484Y518674D01*
X2676Y519242D01*
X2983Y520017D01*
X1449D01*
G01X4212Y533601D02*
Y569488D01*
G01X18497Y571684D02*
X15397D01*
Y572643D01*
X15552Y572949D01*
X15759Y573141D01*
X16172Y573218D01*
X16585Y573141D01*
X16844Y572911D01*
X16999Y572643D01*
Y571684D01*
G01Y572643D02*
X18497Y573218D01*
G01Y575551D02*
X15397D01*
X16017Y575091D01*
G01X18497D02*
Y576011D01*
G01X18032Y577808D02*
X18290Y578038D01*
X18445Y578306D01*
X18497Y578651D01*
X18394Y578996D01*
X18187Y579264D01*
X17825Y579456D01*
X17412Y579494D01*
X16999Y579418D01*
X16740Y579226D01*
X16534Y578958D01*
X16482Y578689D01*
X16534Y578421D01*
X16740Y578076D01*
X15397Y578191D01*
Y579226D01*
G01Y581751D02*
X15500Y581444D01*
X15759Y581214D01*
X16069Y581061D01*
X16482Y580946D01*
X16947Y580908D01*
X17412Y580946D01*
X17825Y581061D01*
X18135Y581214D01*
X18394Y581444D01*
X18497Y581751D01*
X18394Y582058D01*
X18135Y582288D01*
X17825Y582441D01*
X17412Y582556D01*
X16947Y582594D01*
X16482Y582556D01*
X16069Y582441D01*
X15759Y582288D01*
X15500Y582058D01*
X15397Y581751D01*
G01X10077Y571287D02*
Y577487D01*
X13277D01*
Y571287D01*
X10077D01*
G01X4212Y569488D02*
X68778D01*
Y533601D01*
G01X16943Y609223D02*
X16633Y609453D01*
X16478Y609721D01*
X16426Y610028D01*
X16529Y610411D01*
X16788Y610679D01*
X17098Y610756D01*
X17408Y610718D01*
X17666Y610564D01*
X18183Y609798D01*
X18544Y609453D01*
X19061Y609223D01*
X19526Y609146D01*
Y610756D01*
G01X23386Y605216D02*
X15512D01*
G01X23386Y589980D02*
Y605216D01*
G01X3700Y589980D02*
X23386D01*
G01X3700Y605216D02*
Y589980D01*
G01X11575Y605216D02*
X3700D01*
G01X15512D02*
Y607184D01*
G01X11575D02*
Y605216D01*
G01X1732Y607184D02*
Y588011D01*
X25354D01*
Y607184D01*
X1732D01*
G01X23386Y632579D02*
X15512D01*
G01X23386Y617343D02*
Y632579D01*
G01X3700Y617343D02*
X23386D01*
G01X3700Y632579D02*
Y617343D01*
G01X11575Y632579D02*
X3700D01*
G01X15512D02*
Y634547D01*
G01X11575D02*
Y632579D01*
G01X1732Y634547D02*
Y615374D01*
X25354D01*
Y634547D01*
X1732D01*
G01X16943Y636586D02*
X16633Y636816D01*
X16478Y637084D01*
X16426Y637391D01*
X16529Y637774D01*
X16788Y638042D01*
X17098Y638119D01*
X17408Y638081D01*
X17666Y637927D01*
X18183Y637161D01*
X18544Y636816D01*
X19061Y636586D01*
X19526Y636509D01*
Y638119D01*
G01X7386Y682489D02*
X7231Y682642D01*
X6972Y682757D01*
X6611Y682834D01*
X6301Y682757D01*
X6094Y682604D01*
X5939Y682335D01*
Y681300D01*
X9039D01*
Y682565D01*
X8832Y682834D01*
X8522Y682987D01*
X8161Y683064D01*
X7799Y682987D01*
X7489Y682757D01*
X7386Y682489D01*
Y681300D01*
G01X9039Y685282D02*
X8987Y685550D01*
X8832Y685857D01*
X8574Y686049D01*
X8212Y686125D01*
X7851Y686049D01*
X7541Y685819D01*
X7386Y685474D01*
Y685090D01*
X7282Y684860D01*
X7024Y684669D01*
X6662Y684592D01*
X6301Y684707D01*
X6042Y684975D01*
X5939Y685282D01*
X6042Y685589D01*
X6301Y685857D01*
X6662Y685972D01*
X7024Y685895D01*
X7282Y685704D01*
X7386Y685474D01*
Y685090D01*
X7541Y684745D01*
X7851Y684515D01*
X8212Y684439D01*
X8574Y684515D01*
X8832Y684707D01*
X8987Y685014D01*
X9039Y685282D01*
G01X6456Y687654D02*
X6146Y687884D01*
X5991Y688152D01*
X5939Y688459D01*
X6042Y688842D01*
X6301Y689110D01*
X6611Y689187D01*
X6921Y689149D01*
X7179Y688995D01*
X7696Y688229D01*
X8057Y687884D01*
X8574Y687654D01*
X9039Y687577D01*
Y689187D01*
G01X15260Y682489D02*
X15105Y682642D01*
X14846Y682757D01*
X14485Y682834D01*
X14175Y682757D01*
X13968Y682604D01*
X13813Y682335D01*
Y681300D01*
X16913D01*
Y682565D01*
X16706Y682834D01*
X16396Y682987D01*
X16035Y683064D01*
X15673Y682987D01*
X15363Y682757D01*
X15260Y682489D01*
Y681300D01*
G01X16913Y685282D02*
X16861Y685550D01*
X16706Y685857D01*
X16448Y686049D01*
X16086Y686125D01*
X15725Y686049D01*
X15415Y685819D01*
X15260Y685474D01*
Y685090D01*
X15156Y684860D01*
X14898Y684669D01*
X14536Y684592D01*
X14175Y684707D01*
X13916Y684975D01*
X13813Y685282D01*
X13916Y685589D01*
X14175Y685857D01*
X14536Y685972D01*
X14898Y685895D01*
X15156Y685704D01*
X15260Y685474D01*
Y685090D01*
X15415Y684745D01*
X15725Y684515D01*
X16086Y684439D01*
X16448Y684515D01*
X16706Y684707D01*
X16861Y685014D01*
X16913Y685282D01*
G01Y688382D02*
X13813D01*
X14433Y687922D01*
G01X16913D02*
Y688842D01*
G01X26755Y681224D02*
X23655Y682182D01*
X26755Y683140D01*
G01X25670Y682795D02*
Y681569D01*
G01X26755Y685282D02*
X26703Y685550D01*
X26548Y685857D01*
X26290Y686049D01*
X25928Y686125D01*
X25567Y686049D01*
X25257Y685819D01*
X25102Y685474D01*
Y685090D01*
X24998Y684860D01*
X24740Y684669D01*
X24378Y684592D01*
X24017Y684707D01*
X23758Y684975D01*
X23655Y685282D01*
X23758Y685589D01*
X24017Y685857D01*
X24378Y685972D01*
X24740Y685895D01*
X24998Y685704D01*
X25102Y685474D01*
Y685090D01*
X25257Y684745D01*
X25567Y684515D01*
X25928Y684439D01*
X26290Y684515D01*
X26548Y684707D01*
X26703Y685014D01*
X26755Y685282D01*
G01Y688382D02*
X23655D01*
X24275Y687922D01*
G01X26755D02*
Y688842D01*
G01X35822Y1042010D02*
Y690711D01*
X24071D01*
G01X14652Y1035390D02*
X14497Y1035543D01*
X14238Y1035658D01*
X13877Y1035735D01*
X13567Y1035658D01*
X13360Y1035505D01*
X13205Y1035236D01*
Y1034201D01*
X16305D01*
Y1035466D01*
X16098Y1035735D01*
X15788Y1035888D01*
X15427Y1035965D01*
X15065Y1035888D01*
X14755Y1035658D01*
X14652Y1035390D01*
Y1034201D01*
G01X16305Y1038183D02*
X13205D01*
X13825Y1037723D01*
G01X16305D02*
Y1038643D01*
G01X27671Y1033335D02*
X24571Y1034293D01*
X27671Y1035251D01*
G01X26586Y1034906D02*
Y1033680D01*
G01X27671Y1037393D02*
X24571D01*
X25191Y1036933D01*
G01X27671D02*
Y1037853D01*
G01X8442Y1035073D02*
X8287Y1035226D01*
X8028Y1035341D01*
X7667Y1035418D01*
X7357Y1035341D01*
X7150Y1035188D01*
X6995Y1034919D01*
Y1033884D01*
X10095D01*
Y1035149D01*
X9888Y1035418D01*
X9578Y1035571D01*
X9217Y1035648D01*
X8855Y1035571D01*
X8545Y1035341D01*
X8442Y1035073D01*
Y1033884D01*
G01X7512Y1037138D02*
X7202Y1037368D01*
X7047Y1037636D01*
X6995Y1037943D01*
X7098Y1038326D01*
X7357Y1038594D01*
X7667Y1038671D01*
X7977Y1038633D01*
X8235Y1038479D01*
X8752Y1037713D01*
X9113Y1037368D01*
X9630Y1037138D01*
X10095Y1037061D01*
Y1038671D01*
G01X6662Y1052668D02*
X6507Y1052821D01*
X6248Y1052936D01*
X5887Y1053013D01*
X5577Y1052936D01*
X5370Y1052783D01*
X5215Y1052514D01*
Y1051479D01*
X8315D01*
Y1052744D01*
X8108Y1053013D01*
X7798Y1053166D01*
X7437Y1053243D01*
X7075Y1053166D01*
X6765Y1052936D01*
X6662Y1052668D01*
Y1051479D01*
G01X8315Y1055461D02*
X8263Y1055729D01*
X8108Y1056036D01*
X7850Y1056228D01*
X7488Y1056304D01*
X7127Y1056228D01*
X6817Y1055998D01*
X6662Y1055653D01*
Y1055269D01*
X6558Y1055039D01*
X6300Y1054848D01*
X5938Y1054771D01*
X5577Y1054886D01*
X5318Y1055154D01*
X5215Y1055461D01*
X5318Y1055768D01*
X5577Y1056036D01*
X5938Y1056151D01*
X6300Y1056074D01*
X6558Y1055883D01*
X6662Y1055653D01*
Y1055269D01*
X6817Y1054924D01*
X7127Y1054694D01*
X7488Y1054618D01*
X7850Y1054694D01*
X8108Y1054886D01*
X8263Y1055193D01*
X8315Y1055461D01*
G01X5732Y1057833D02*
X5422Y1058063D01*
X5267Y1058331D01*
X5215Y1058638D01*
X5318Y1059021D01*
X5577Y1059289D01*
X5887Y1059366D01*
X6197Y1059328D01*
X6455Y1059174D01*
X6972Y1058408D01*
X7333Y1058063D01*
X7850Y1057833D01*
X8315Y1057756D01*
Y1059366D01*
G01X12188Y1052405D02*
X12033Y1052558D01*
X11774Y1052673D01*
X11413Y1052750D01*
X11103Y1052673D01*
X10896Y1052520D01*
X10741Y1052251D01*
Y1051216D01*
X13841D01*
Y1052481D01*
X13634Y1052750D01*
X13324Y1052903D01*
X12963Y1052980D01*
X12601Y1052903D01*
X12291Y1052673D01*
X12188Y1052405D01*
Y1051216D01*
G01X13841Y1055198D02*
X13789Y1055466D01*
X13634Y1055773D01*
X13376Y1055965D01*
X13014Y1056041D01*
X12653Y1055965D01*
X12343Y1055735D01*
X12188Y1055390D01*
Y1055006D01*
X12084Y1054776D01*
X11826Y1054585D01*
X11464Y1054508D01*
X11103Y1054623D01*
X10844Y1054891D01*
X10741Y1055198D01*
X10844Y1055505D01*
X11103Y1055773D01*
X11464Y1055888D01*
X11826Y1055811D01*
X12084Y1055620D01*
X12188Y1055390D01*
Y1055006D01*
X12343Y1054661D01*
X12653Y1054431D01*
X13014Y1054355D01*
X13376Y1054431D01*
X13634Y1054623D01*
X13789Y1054930D01*
X13841Y1055198D01*
G01Y1058298D02*
X10741D01*
X11361Y1057838D01*
G01X13841D02*
Y1058758D01*
G01X35826Y1400275D02*
Y1048976D01*
X24075D01*
G01X16122Y1403536D02*
X15967Y1403689D01*
X15708Y1403804D01*
X15347Y1403881D01*
X15037Y1403804D01*
X14830Y1403651D01*
X14675Y1403382D01*
Y1402347D01*
X17775D01*
Y1403612D01*
X17568Y1403881D01*
X17258Y1404034D01*
X16897Y1404111D01*
X16535Y1404034D01*
X16225Y1403804D01*
X16122Y1403536D01*
Y1402347D01*
G01X17775Y1406329D02*
X14675D01*
X15295Y1405869D01*
G01X17775D02*
Y1406789D01*
G01X26433Y1403060D02*
X23333Y1404018D01*
X26433Y1404976D01*
G01X25348Y1404631D02*
Y1403405D01*
G01X26433Y1407118D02*
X23333D01*
X23953Y1406658D01*
G01X26433D02*
Y1407578D01*
G01X8248Y1403536D02*
X8093Y1403689D01*
X7834Y1403804D01*
X7473Y1403881D01*
X7163Y1403804D01*
X6956Y1403651D01*
X6801Y1403382D01*
Y1402347D01*
X9901D01*
Y1403612D01*
X9694Y1403881D01*
X9384Y1404034D01*
X9023Y1404111D01*
X8661Y1404034D01*
X8351Y1403804D01*
X8248Y1403536D01*
Y1402347D01*
G01X7318Y1405601D02*
X7008Y1405831D01*
X6853Y1406099D01*
X6801Y1406406D01*
X6904Y1406789D01*
X7163Y1407057D01*
X7473Y1407134D01*
X7783Y1407096D01*
X8041Y1406942D01*
X8558Y1406176D01*
X8919Y1405831D01*
X9436Y1405601D01*
X9901Y1405524D01*
Y1407134D01*
G01X16943Y1481271D02*
X16633Y1481501D01*
X16478Y1481769D01*
X16426Y1482076D01*
X16529Y1482459D01*
X16788Y1482727D01*
X17098Y1482804D01*
X17408Y1482766D01*
X17666Y1482612D01*
X18183Y1481846D01*
X18544Y1481501D01*
X19061Y1481271D01*
X19526Y1481194D01*
Y1482804D01*
G01X23386Y1477264D02*
X15512D01*
G01X23386Y1462028D02*
Y1477264D01*
G01X3700Y1462028D02*
X23386D01*
G01X3700Y1477264D02*
Y1462028D01*
G01X11575Y1477264D02*
X3700D01*
G01X15512D02*
Y1479232D01*
G01X11575D02*
Y1477264D01*
G01X1732Y1479232D02*
Y1460059D01*
X25354D01*
Y1479232D01*
X1732D01*
G01X23386Y1504626D02*
X15512D01*
G01X23386Y1489390D02*
Y1504626D01*
G01X3700Y1489390D02*
X23386D01*
G01X3700Y1504626D02*
Y1489390D01*
G01X11575Y1504626D02*
X3700D01*
G01X15512D02*
Y1506594D01*
G01X11575D02*
Y1504626D01*
G01X1732Y1506594D02*
Y1487421D01*
X25354D01*
Y1506594D01*
X1732D01*
G01X16943Y1508633D02*
X16633Y1508863D01*
X16478Y1509131D01*
X16426Y1509438D01*
X16529Y1509821D01*
X16788Y1510089D01*
X17098Y1510166D01*
X17408Y1510128D01*
X17666Y1509974D01*
X18183Y1509208D01*
X18544Y1508863D01*
X19061Y1508633D01*
X19526Y1508556D01*
Y1510166D01*
G01X17970Y1539752D02*
X14870D01*
Y1540711D01*
X15025Y1541017D01*
X15232Y1541209D01*
X15645Y1541286D01*
X16058Y1541209D01*
X16317Y1540979D01*
X16472Y1540711D01*
Y1539752D01*
G01Y1540711D02*
X17970Y1541286D01*
G01Y1543619D02*
X14870D01*
X15490Y1543159D01*
G01X17970D02*
Y1544079D01*
G01X17505Y1545876D02*
X17763Y1546106D01*
X17918Y1546374D01*
X17970Y1546719D01*
X17867Y1547064D01*
X17660Y1547332D01*
X17298Y1547524D01*
X16885Y1547562D01*
X16472Y1547486D01*
X16213Y1547294D01*
X16007Y1547026D01*
X15955Y1546757D01*
X16007Y1546489D01*
X16213Y1546144D01*
X14870Y1546259D01*
Y1547294D01*
G01X17970Y1549819D02*
X14870D01*
X15490Y1549359D01*
G01X17970D02*
Y1550279D01*
G01X14884Y1553634D02*
Y1559834D01*
X18084D01*
Y1553634D01*
X14884D01*
G01X13112Y1539750D02*
X10012D01*
Y1540709D01*
X10167Y1541015D01*
X10374Y1541207D01*
X10787Y1541284D01*
X11200Y1541207D01*
X11459Y1540977D01*
X11614Y1540709D01*
Y1539750D01*
G01Y1540709D02*
X13112Y1541284D01*
G01Y1543617D02*
X10012D01*
X10632Y1543157D01*
G01X13112D02*
Y1544077D01*
G01X12647Y1545874D02*
X12905Y1546104D01*
X13060Y1546372D01*
X13112Y1546717D01*
X13009Y1547062D01*
X12802Y1547330D01*
X12440Y1547522D01*
X12027Y1547560D01*
X11614Y1547484D01*
X11355Y1547292D01*
X11149Y1547024D01*
X11097Y1546755D01*
X11149Y1546487D01*
X11355Y1546142D01*
X10012Y1546257D01*
Y1547292D01*
G01X10529Y1549089D02*
X10219Y1549319D01*
X10064Y1549587D01*
X10012Y1549894D01*
X10115Y1550277D01*
X10374Y1550545D01*
X10684Y1550622D01*
X10994Y1550584D01*
X11252Y1550430D01*
X11769Y1549664D01*
X12130Y1549319D01*
X12647Y1549089D01*
X13112Y1549012D01*
Y1550622D01*
G01X9485Y1553766D02*
Y1559966D01*
X12685D01*
Y1553766D01*
X9485D01*
G01X68778Y1562205D02*
X4212D01*
Y1598092D01*
G01X1983Y1624408D02*
X2213Y1624718D01*
X2481Y1624873D01*
X2788Y1624925D01*
X3171Y1624822D01*
X3439Y1624563D01*
X3516Y1624253D01*
X3478Y1623943D01*
X3324Y1623685D01*
X2558Y1623168D01*
X2213Y1622807D01*
X1983Y1622290D01*
X1906Y1621825D01*
X3516D01*
G01X2861Y1615675D02*
Y1618775D01*
X2401Y1618155D01*
G01Y1615675D02*
X3321D01*
G01X4212Y1608192D02*
Y1627953D01*
X68778D01*
Y1608192D01*
G01X20909Y1652987D02*
X21139Y1653297D01*
X21407Y1653452D01*
X21714Y1653504D01*
X22097Y1653401D01*
X22365Y1653142D01*
X22442Y1652832D01*
X22404Y1652522D01*
X22250Y1652264D01*
X21484Y1651747D01*
X21139Y1651386D01*
X20909Y1650869D01*
X20832Y1650404D01*
X22442D01*
G01X24737Y1653504D02*
X24430Y1653401D01*
X24200Y1653142D01*
X24047Y1652832D01*
X23932Y1652419D01*
X23894Y1651954D01*
X23932Y1651489D01*
X24047Y1651076D01*
X24200Y1650766D01*
X24430Y1650507D01*
X24737Y1650404D01*
X25044Y1650507D01*
X25274Y1650766D01*
X25427Y1651076D01*
X25542Y1651489D01*
X25580Y1651954D01*
X25542Y1652419D01*
X25427Y1652832D01*
X25274Y1653142D01*
X25044Y1653401D01*
X24737Y1653504D01*
G01X4178Y1631179D02*
X4370Y1630869D01*
X4600Y1630662D01*
X4868Y1630559D01*
X5175Y1630662D01*
X5405Y1630869D01*
X5635Y1631179D01*
X5712Y1631592D01*
Y1633659D01*
G01X7317Y1633142D02*
X7547Y1633452D01*
X7815Y1633607D01*
X8122Y1633659D01*
X8505Y1633556D01*
X8773Y1633297D01*
X8850Y1632987D01*
X8812Y1632677D01*
X8658Y1632419D01*
X7892Y1631902D01*
X7547Y1631541D01*
X7317Y1631024D01*
X7240Y1630559D01*
X8850D01*
G01X11145D02*
X11413Y1630611D01*
X11720Y1630766D01*
X11912Y1631024D01*
X11988Y1631386D01*
X11912Y1631747D01*
X11682Y1632057D01*
X11337Y1632212D01*
X10953D01*
X10723Y1632316D01*
X10532Y1632574D01*
X10455Y1632936D01*
X10570Y1633297D01*
X10838Y1633556D01*
X11145Y1633659D01*
X11452Y1633556D01*
X11720Y1633297D01*
X11835Y1632936D01*
X11758Y1632574D01*
X11567Y1632316D01*
X11337Y1632212D01*
X10953D01*
X10608Y1632057D01*
X10378Y1631747D01*
X10302Y1631386D01*
X10378Y1631024D01*
X10570Y1630766D01*
X10877Y1630611D01*
X11145Y1630559D01*
G01X54702Y1657457D02*
Y1655882D01*
X16119D01*
Y1657457D01*
G01Y1829110D02*
X54702D01*
Y1657457D01*
X16119D01*
Y1830685D01*
X54702D01*
Y1829110D01*
G01X16119Y1750370D02*
X9820D01*
Y1736197D01*
X16119D01*
G01X9992Y1817623D02*
Y1820723D01*
X9532Y1820103D01*
G01Y1817623D02*
X10452D01*
G01X13092D02*
Y1820723D01*
X12632Y1820103D01*
G01Y1817623D02*
X13552D01*
G01X23698Y1834558D02*
X23890Y1834248D01*
X24120Y1834041D01*
X24388Y1833938D01*
X24695Y1834041D01*
X24925Y1834248D01*
X25155Y1834558D01*
X25232Y1834971D01*
Y1837038D01*
G01X26837Y1836521D02*
X27067Y1836831D01*
X27335Y1836986D01*
X27642Y1837038D01*
X28025Y1836935D01*
X28293Y1836676D01*
X28370Y1836366D01*
X28332Y1836056D01*
X28178Y1835798D01*
X27412Y1835281D01*
X27067Y1834920D01*
X26837Y1834403D01*
X26760Y1833938D01*
X28370D01*
G01X30665Y1837038D02*
X30358Y1836935D01*
X30128Y1836676D01*
X29975Y1836366D01*
X29860Y1835953D01*
X29822Y1835488D01*
X29860Y1835023D01*
X29975Y1834610D01*
X30128Y1834300D01*
X30358Y1834041D01*
X30665Y1833938D01*
X30972Y1834041D01*
X31202Y1834300D01*
X31355Y1834610D01*
X31470Y1835023D01*
X31508Y1835488D01*
X31470Y1835953D01*
X31355Y1836366D01*
X31202Y1836676D01*
X30972Y1836935D01*
X30665Y1837038D01*
G01X66003Y1896779D02*
X4467D01*
Y1962291D01*
X66003D01*
Y1896779D01*
G01X1933Y1961528D02*
X2163Y1961838D01*
X2431Y1961993D01*
X2738Y1962045D01*
X3121Y1961942D01*
X3389Y1961683D01*
X3466Y1961373D01*
X3428Y1961063D01*
X3274Y1960805D01*
X2508Y1960288D01*
X2163Y1959927D01*
X1933Y1959410D01*
X1856Y1958945D01*
X3466D01*
G01X2861Y1953045D02*
Y1956145D01*
X2401Y1955525D01*
G01Y1953045D02*
X3321D01*
G01X66003Y2001149D02*
X4467D01*
Y2066661D01*
X66003D01*
Y2001149D01*
G01X1407Y2062411D02*
X1637Y2062721D01*
X1905Y2062876D01*
X2212Y2062928D01*
X2595Y2062825D01*
X2863Y2062566D01*
X2940Y2062256D01*
X2902Y2061946D01*
X2748Y2061688D01*
X1982Y2061171D01*
X1637Y2060810D01*
X1407Y2060293D01*
X1330Y2059828D01*
X2940D01*
G01X2855Y2053662D02*
Y2056762D01*
X2395Y2056142D01*
G01Y2053662D02*
X3315D01*
G01X96850Y114960D02*
G03I-31496J0D01*
G01X26263Y90322D02*
X26455Y90012D01*
X26685Y89805D01*
X26953Y89702D01*
X27260Y89805D01*
X27490Y90012D01*
X27720Y90322D01*
X27797Y90735D01*
Y92802D01*
G01X30130Y89702D02*
Y92802D01*
X29670Y92182D01*
G01Y89702D02*
X30590D01*
G01X32578Y90064D02*
X32847Y89805D01*
X33153Y89702D01*
X33460Y89805D01*
X33728Y90115D01*
X33920Y90580D01*
X33997Y91045D01*
Y91614D01*
X33920Y92079D01*
X33728Y92492D01*
X33498Y92699D01*
X33230Y92802D01*
X32923Y92699D01*
X32693Y92492D01*
X32540Y92182D01*
X32463Y91769D01*
X32540Y91407D01*
X32732Y91045D01*
X32962Y90839D01*
X33230Y90787D01*
X33537Y90890D01*
X33767Y91149D01*
X33997Y91614D01*
G01X34553Y296493D02*
X34745Y296183D01*
X34975Y295976D01*
X35243Y295873D01*
X35550Y295976D01*
X35780Y296183D01*
X36010Y296493D01*
X36087Y296906D01*
Y298973D01*
G01X37692Y298456D02*
X37922Y298766D01*
X38190Y298921D01*
X38497Y298973D01*
X38880Y298870D01*
X39148Y298611D01*
X39225Y298301D01*
X39187Y297991D01*
X39033Y297733D01*
X38267Y297216D01*
X37922Y296855D01*
X37692Y296338D01*
X37615Y295873D01*
X39225D01*
G01X40677Y296493D02*
X40907Y296131D01*
X41213Y295925D01*
X41558Y295873D01*
X41865Y295925D01*
X42172Y296183D01*
X42363Y296493D01*
X42402Y296803D01*
X42325Y297165D01*
X42057Y297423D01*
X41788Y297526D01*
X41443D01*
G01X41788D02*
X42018Y297681D01*
X42210Y297940D01*
X42287Y298250D01*
X42210Y298560D01*
X42018Y298818D01*
X41673Y298973D01*
X41328Y298921D01*
X40983Y298715D01*
G01X96850Y464960D02*
G03I-31496J0D01*
G01X34643Y487688D02*
Y490788D01*
G01X36253D02*
Y487688D01*
G01Y489238D02*
X34643D01*
G01X38548Y487688D02*
Y490788D01*
X38088Y490168D01*
G01Y487688D02*
X39008D01*
G01X41648Y490788D02*
X41341Y490685D01*
X41111Y490426D01*
X40958Y490116D01*
X40843Y489703D01*
X40805Y489238D01*
X40843Y488773D01*
X40958Y488360D01*
X41111Y488050D01*
X41341Y487791D01*
X41648Y487688D01*
X41955Y487791D01*
X42185Y488050D01*
X42338Y488360D01*
X42453Y488773D01*
X42491Y489238D01*
X42453Y489703D01*
X42338Y490116D01*
X42185Y490426D01*
X41955Y490685D01*
X41648Y490788D01*
G01X29057Y594052D02*
X29367Y594244D01*
X29574Y594474D01*
X29677Y594742D01*
X29574Y595049D01*
X29367Y595279D01*
X29057Y595509D01*
X28644Y595586D01*
X26577D01*
G01X29057Y597076D02*
X29419Y597306D01*
X29625Y597612D01*
X29677Y597957D01*
X29625Y598264D01*
X29367Y598571D01*
X29057Y598762D01*
X28747Y598801D01*
X28385Y598724D01*
X28127Y598456D01*
X28024Y598187D01*
Y597842D01*
G01Y598187D02*
X27869Y598417D01*
X27610Y598609D01*
X27300Y598686D01*
X26990Y598609D01*
X26732Y598417D01*
X26577Y598072D01*
X26629Y597727D01*
X26835Y597382D01*
G01X29057Y600176D02*
X29419Y600406D01*
X29625Y600712D01*
X29677Y601057D01*
X29625Y601364D01*
X29367Y601671D01*
X29057Y601862D01*
X28747Y601901D01*
X28385Y601824D01*
X28127Y601556D01*
X28024Y601287D01*
Y600942D01*
G01Y601287D02*
X27869Y601517D01*
X27610Y601709D01*
X27300Y601786D01*
X26990Y601709D01*
X26732Y601517D01*
X26577Y601172D01*
X26629Y600827D01*
X26835Y600482D01*
G01X29057Y622275D02*
X29367Y622467D01*
X29574Y622697D01*
X29677Y622965D01*
X29574Y623272D01*
X29367Y623502D01*
X29057Y623732D01*
X28644Y623809D01*
X26577D01*
G01X29057Y625299D02*
X29419Y625529D01*
X29625Y625835D01*
X29677Y626180D01*
X29625Y626487D01*
X29367Y626794D01*
X29057Y626985D01*
X28747Y627024D01*
X28385Y626947D01*
X28127Y626679D01*
X28024Y626410D01*
Y626065D01*
G01Y626410D02*
X27869Y626640D01*
X27610Y626832D01*
X27300Y626909D01*
X26990Y626832D01*
X26732Y626640D01*
X26577Y626295D01*
X26629Y625950D01*
X26835Y625605D01*
G01X26577Y629242D02*
X26680Y628935D01*
X26939Y628705D01*
X27249Y628552D01*
X27662Y628437D01*
X28127Y628399D01*
X28592Y628437D01*
X29005Y628552D01*
X29315Y628705D01*
X29574Y628935D01*
X29677Y629242D01*
X29574Y629549D01*
X29315Y629779D01*
X29005Y629932D01*
X28592Y630047D01*
X28127Y630085D01*
X27662Y630047D01*
X27249Y629932D01*
X26939Y629779D01*
X26680Y629549D01*
X26577Y629242D01*
G01X34630Y681224D02*
X31530Y682182D01*
X34630Y683140D01*
G01X33545Y682795D02*
Y681569D01*
G01X34630Y685282D02*
X34578Y685550D01*
X34423Y685857D01*
X34165Y686049D01*
X33803Y686125D01*
X33442Y686049D01*
X33132Y685819D01*
X32977Y685474D01*
Y685090D01*
X32873Y684860D01*
X32615Y684669D01*
X32253Y684592D01*
X31892Y684707D01*
X31633Y684975D01*
X31530Y685282D01*
X31633Y685589D01*
X31892Y685857D01*
X32253Y685972D01*
X32615Y685895D01*
X32873Y685704D01*
X32977Y685474D01*
Y685090D01*
X33132Y684745D01*
X33442Y684515D01*
X33803Y684439D01*
X34165Y684515D01*
X34423Y684707D01*
X34578Y685014D01*
X34630Y685282D01*
G01X32047Y687654D02*
X31737Y687884D01*
X31582Y688152D01*
X31530Y688459D01*
X31633Y688842D01*
X31892Y689110D01*
X32202Y689187D01*
X32512Y689149D01*
X32770Y688995D01*
X33287Y688229D01*
X33648Y687884D01*
X34165Y687654D01*
X34630Y687577D01*
Y689187D01*
G01X96850Y814960D02*
G03I-31496J0D01*
G01X33053Y1033480D02*
X29953Y1034438D01*
X33053Y1035396D01*
G01X31968Y1035051D02*
Y1033825D01*
G01X30470Y1036810D02*
X30160Y1037040D01*
X30005Y1037308D01*
X29953Y1037615D01*
X30056Y1037998D01*
X30315Y1038266D01*
X30625Y1038343D01*
X30935Y1038305D01*
X31193Y1038151D01*
X31710Y1037385D01*
X32071Y1037040D01*
X32588Y1036810D01*
X33053Y1036733D01*
Y1038343D01*
G01X34390Y1051200D02*
X31290Y1052158D01*
X34390Y1053116D01*
G01X33305Y1052771D02*
Y1051545D01*
G01X34390Y1055258D02*
X34338Y1055526D01*
X34183Y1055833D01*
X33925Y1056025D01*
X33563Y1056101D01*
X33202Y1056025D01*
X32892Y1055795D01*
X32737Y1055450D01*
Y1055066D01*
X32633Y1054836D01*
X32375Y1054645D01*
X32013Y1054568D01*
X31652Y1054683D01*
X31393Y1054951D01*
X31290Y1055258D01*
X31393Y1055565D01*
X31652Y1055833D01*
X32013Y1055948D01*
X32375Y1055871D01*
X32633Y1055680D01*
X32737Y1055450D01*
Y1055066D01*
X32892Y1054721D01*
X33202Y1054491D01*
X33563Y1054415D01*
X33925Y1054491D01*
X34183Y1054683D01*
X34338Y1054990D01*
X34390Y1055258D01*
G01Y1058358D02*
X31290D01*
X31910Y1057898D01*
G01X34390D02*
Y1058818D01*
G01X96850Y1164960D02*
G03I-31496J0D01*
G01X51931Y1304205D02*
Y1298005D01*
X48731D01*
Y1304205D01*
X51931D01*
G01X34308Y1403060D02*
X31208Y1404018D01*
X34308Y1404976D01*
G01X33223Y1404631D02*
Y1403405D01*
G01X31725Y1406390D02*
X31415Y1406620D01*
X31260Y1406888D01*
X31208Y1407195D01*
X31311Y1407578D01*
X31570Y1407846D01*
X31880Y1407923D01*
X32190Y1407885D01*
X32448Y1407731D01*
X32965Y1406965D01*
X33326Y1406620D01*
X33843Y1406390D01*
X34308Y1406313D01*
Y1407923D01*
G01X29574Y1465402D02*
X29884Y1465594D01*
X30091Y1465824D01*
X30194Y1466092D01*
X30091Y1466399D01*
X29884Y1466629D01*
X29574Y1466859D01*
X29161Y1466936D01*
X27094D01*
G01X29574Y1468426D02*
X29936Y1468656D01*
X30142Y1468962D01*
X30194Y1469307D01*
X30142Y1469614D01*
X29884Y1469921D01*
X29574Y1470112D01*
X29264Y1470151D01*
X28902Y1470074D01*
X28644Y1469806D01*
X28541Y1469537D01*
Y1469192D01*
G01Y1469537D02*
X28386Y1469767D01*
X28127Y1469959D01*
X27817Y1470036D01*
X27507Y1469959D01*
X27249Y1469767D01*
X27094Y1469422D01*
X27146Y1469077D01*
X27352Y1468732D01*
G01X30194Y1472369D02*
X27094D01*
X27714Y1471909D01*
G01X30194D02*
Y1472829D01*
G01X96850Y1514960D02*
G03I-31496J0D01*
G01X29432Y1492912D02*
X29742Y1493104D01*
X29949Y1493334D01*
X30052Y1493602D01*
X29949Y1493909D01*
X29742Y1494139D01*
X29432Y1494369D01*
X29019Y1494446D01*
X26952D01*
G01X29432Y1495936D02*
X29794Y1496166D01*
X30000Y1496472D01*
X30052Y1496817D01*
X30000Y1497124D01*
X29742Y1497431D01*
X29432Y1497622D01*
X29122Y1497661D01*
X28760Y1497584D01*
X28502Y1497316D01*
X28399Y1497047D01*
Y1496702D01*
G01Y1497047D02*
X28244Y1497277D01*
X27985Y1497469D01*
X27675Y1497546D01*
X27365Y1497469D01*
X27107Y1497277D01*
X26952Y1496932D01*
X27004Y1496587D01*
X27210Y1496242D01*
G01X27469Y1499151D02*
X27159Y1499381D01*
X27004Y1499649D01*
X26952Y1499956D01*
X27055Y1500339D01*
X27314Y1500607D01*
X27624Y1500684D01*
X27934Y1500646D01*
X28192Y1500492D01*
X28709Y1499726D01*
X29070Y1499381D01*
X29587Y1499151D01*
X30052Y1499074D01*
Y1500684D01*
G01X40299Y1541627D02*
Y1544727D01*
G01X41909D02*
Y1541627D01*
G01Y1543177D02*
X40299D01*
G01X43476Y1542919D02*
X43744Y1543280D01*
X43974Y1543487D01*
X44281Y1543590D01*
X44549Y1543487D01*
X44741Y1543280D01*
X44894Y1542970D01*
X44932Y1542609D01*
X44894Y1542299D01*
X44741Y1541989D01*
X44511Y1541730D01*
X44242Y1541627D01*
X43936Y1541730D01*
X43667Y1542040D01*
X43514Y1542505D01*
X43476Y1543022D01*
X43552Y1543694D01*
X43667Y1544055D01*
X43859Y1544417D01*
X44127Y1544675D01*
X44396Y1544727D01*
X44664Y1544624D01*
X44856Y1544365D01*
G01X44793Y1649615D02*
Y1652715D01*
X44333Y1652095D01*
G01Y1649615D02*
X45253D01*
G01X47893Y1652715D02*
X47586Y1652612D01*
X47356Y1652353D01*
X47203Y1652043D01*
X47088Y1651630D01*
X47050Y1651165D01*
X47088Y1650700D01*
X47203Y1650287D01*
X47356Y1649977D01*
X47586Y1649718D01*
X47893Y1649615D01*
X48200Y1649718D01*
X48430Y1649977D01*
X48583Y1650287D01*
X48698Y1650700D01*
X48736Y1651165D01*
X48698Y1651630D01*
X48583Y1652043D01*
X48430Y1652353D01*
X48200Y1652612D01*
X47893Y1652715D01*
G01X96850Y1864960D02*
G03I-31496J0D01*
G01X40339Y1833289D02*
Y1836389D01*
X39879Y1835769D01*
G01Y1833289D02*
X40799D01*
G01X40299Y1891627D02*
Y1894727D01*
G01X41909D02*
Y1891627D01*
G01Y1893177D02*
X40299D01*
G01X44204Y1891627D02*
X44472Y1891679D01*
X44779Y1891834D01*
X44971Y1892092D01*
X45047Y1892454D01*
X44971Y1892815D01*
X44741Y1893125D01*
X44396Y1893280D01*
X44012D01*
X43782Y1893384D01*
X43591Y1893642D01*
X43514Y1894004D01*
X43629Y1894365D01*
X43897Y1894624D01*
X44204Y1894727D01*
X44511Y1894624D01*
X44779Y1894365D01*
X44894Y1894004D01*
X44817Y1893642D01*
X44626Y1893384D01*
X44396Y1893280D01*
X44012D01*
X43667Y1893125D01*
X43437Y1892815D01*
X43361Y1892454D01*
X43437Y1892092D01*
X43629Y1891834D01*
X43936Y1891679D01*
X44204Y1891627D01*
G01X27862Y1969165D02*
X28054Y1968855D01*
X28284Y1968648D01*
X28552Y1968545D01*
X28859Y1968648D01*
X29089Y1968855D01*
X29319Y1969165D01*
X29396Y1969578D01*
Y1971645D01*
G01X31001Y1971128D02*
X31231Y1971438D01*
X31499Y1971593D01*
X31806Y1971645D01*
X32189Y1971542D01*
X32457Y1971283D01*
X32534Y1970973D01*
X32496Y1970663D01*
X32342Y1970405D01*
X31576Y1969888D01*
X31231Y1969527D01*
X31001Y1969010D01*
X30924Y1968545D01*
X32534D01*
G01X34101Y1971128D02*
X34331Y1971438D01*
X34599Y1971593D01*
X34906Y1971645D01*
X35289Y1971542D01*
X35557Y1971283D01*
X35634Y1970973D01*
X35596Y1970663D01*
X35442Y1970405D01*
X34676Y1969888D01*
X34331Y1969527D01*
X34101Y1969010D01*
X34024Y1968545D01*
X35634D01*
G01X35868Y1995601D02*
X36060Y1995291D01*
X36290Y1995084D01*
X36558Y1994981D01*
X36865Y1995084D01*
X37095Y1995291D01*
X37325Y1995601D01*
X37402Y1996014D01*
Y1998081D01*
G01X39007Y1997564D02*
X39237Y1997874D01*
X39505Y1998029D01*
X39812Y1998081D01*
X40195Y1997978D01*
X40463Y1997719D01*
X40540Y1997409D01*
X40502Y1997099D01*
X40348Y1996841D01*
X39582Y1996324D01*
X39237Y1995963D01*
X39007Y1995446D01*
X38930Y1994981D01*
X40540D01*
G01X43295D02*
Y1998081D01*
X41877Y1995859D01*
X43793D01*
G01X67475Y26606D02*
X67705Y26916D01*
X67973Y27071D01*
X68280Y27123D01*
X68663Y27020D01*
X68931Y26761D01*
X69008Y26451D01*
X68970Y26141D01*
X68816Y25883D01*
X68050Y25366D01*
X67705Y25005D01*
X67475Y24488D01*
X67398Y24023D01*
X69008D01*
G01X68003Y29923D02*
Y33023D01*
X67543Y32403D01*
G01Y29923D02*
X68463D01*
G01X71012Y163235D02*
Y360085D01*
X94634D01*
Y163235D01*
X71012D01*
G01X68035Y215643D02*
X68303Y215695D01*
X68610Y215850D01*
X68802Y216108D01*
X68878Y216470D01*
X68802Y216831D01*
X68572Y217141D01*
X68227Y217296D01*
X67843D01*
X67613Y217400D01*
X67422Y217658D01*
X67345Y218020D01*
X67460Y218381D01*
X67728Y218640D01*
X68035Y218743D01*
X68342Y218640D01*
X68610Y218381D01*
X68725Y218020D01*
X68648Y217658D01*
X68457Y217400D01*
X68227Y217296D01*
X67843D01*
X67498Y217141D01*
X67268Y216831D01*
X67192Y216470D01*
X67268Y216108D01*
X67460Y215850D01*
X67767Y215695D01*
X68035Y215643D01*
G01X67958Y205943D02*
X68035Y206615D01*
X68150Y207183D01*
X68303Y207700D01*
X68495Y208268D01*
X68802Y209043D01*
X67268D01*
G01X67538Y235700D02*
X67768Y236010D01*
X68036Y236165D01*
X68343Y236217D01*
X68726Y236114D01*
X68994Y235855D01*
X69071Y235545D01*
X69033Y235235D01*
X68879Y234977D01*
X68113Y234460D01*
X67768Y234099D01*
X67538Y233582D01*
X67461Y233117D01*
X69071D01*
G01X68003Y246537D02*
Y249637D01*
X67543Y249017D01*
G01Y246537D02*
X68463D01*
G01X67958Y414801D02*
X68035Y415473D01*
X68150Y416041D01*
X68303Y416558D01*
X68495Y417126D01*
X68802Y417901D01*
X67268D01*
G01X68035Y424501D02*
X68303Y424553D01*
X68610Y424708D01*
X68802Y424966D01*
X68878Y425328D01*
X68802Y425689D01*
X68572Y425999D01*
X68227Y426154D01*
X67843D01*
X67613Y426258D01*
X67422Y426516D01*
X67345Y426878D01*
X67460Y427239D01*
X67728Y427498D01*
X68035Y427601D01*
X68342Y427498D01*
X68610Y427239D01*
X68725Y426878D01*
X68648Y426516D01*
X68457Y426258D01*
X68227Y426154D01*
X67843D01*
X67498Y425999D01*
X67268Y425689D01*
X67192Y425328D01*
X67268Y424966D01*
X67460Y424708D01*
X67767Y424553D01*
X68035Y424501D01*
G01X70018Y507522D02*
X70248Y507832D01*
X70516Y507987D01*
X70823Y508039D01*
X71206Y507936D01*
X71474Y507677D01*
X71551Y507367D01*
X71513Y507057D01*
X71359Y506799D01*
X70593Y506282D01*
X70248Y505921D01*
X70018Y505404D01*
X69941Y504939D01*
X71551D01*
G01X71535Y513623D02*
Y516723D01*
X71075Y516103D01*
G01Y513623D02*
X71995D01*
G01X55469Y571586D02*
X52369D01*
Y572545D01*
X52524Y572851D01*
X52731Y573043D01*
X53144Y573120D01*
X53557Y573043D01*
X53816Y572813D01*
X53971Y572545D01*
Y571586D01*
G01Y572545D02*
X55469Y573120D01*
G01Y575453D02*
X52369D01*
X52989Y574993D01*
G01X55469D02*
Y575913D01*
G01Y579013D02*
X52369D01*
X54591Y577595D01*
Y579511D01*
G01X55469Y581653D02*
X55417Y581921D01*
X55262Y582228D01*
X55004Y582420D01*
X54642Y582496D01*
X54281Y582420D01*
X53971Y582190D01*
X53816Y581845D01*
Y581461D01*
X53712Y581231D01*
X53454Y581040D01*
X53092Y580963D01*
X52731Y581078D01*
X52472Y581346D01*
X52369Y581653D01*
X52472Y581960D01*
X52731Y582228D01*
X53092Y582343D01*
X53454Y582266D01*
X53712Y582075D01*
X53816Y581845D01*
Y581461D01*
X53971Y581116D01*
X54281Y580886D01*
X54642Y580810D01*
X55004Y580886D01*
X55262Y581078D01*
X55417Y581385D01*
X55469Y581653D01*
G01X60350Y578541D02*
Y572341D01*
X57150D01*
Y578541D01*
X60350D01*
G01X68915Y570896D02*
X65815D01*
Y571855D01*
X65970Y572161D01*
X66177Y572353D01*
X66590Y572430D01*
X67003Y572353D01*
X67262Y572123D01*
X67417Y571855D01*
Y570896D01*
G01Y571855D02*
X68915Y572430D01*
G01Y574763D02*
X65815D01*
X66435Y574303D01*
G01X68915D02*
Y575223D01*
G01Y578323D02*
X65815D01*
X68037Y576905D01*
Y578821D01*
G01X68553Y580311D02*
X68812Y580580D01*
X68915Y580886D01*
X68812Y581193D01*
X68502Y581461D01*
X68037Y581653D01*
X67572Y581730D01*
X67003D01*
X66538Y581653D01*
X66125Y581461D01*
X65918Y581231D01*
X65815Y580963D01*
X65918Y580656D01*
X66125Y580426D01*
X66435Y580273D01*
X66848Y580196D01*
X67210Y580273D01*
X67572Y580465D01*
X67778Y580695D01*
X67830Y580963D01*
X67727Y581270D01*
X67468Y581500D01*
X67003Y581730D01*
G01X65420Y578607D02*
Y572407D01*
X62220D01*
Y578607D01*
X65420D01*
G01X71536Y618991D02*
X66536D01*
Y620511D01*
X66786Y621018D01*
X67369Y621398D01*
X68036Y621525D01*
X68703Y621398D01*
X69203Y621081D01*
X69453Y620511D01*
Y618991D01*
G01X71703Y624218D02*
X66536Y626498D01*
G01X71536Y629001D02*
X66536D01*
X71536Y631915D01*
X66536D01*
G01X71703Y635558D02*
X71619Y635431D01*
X71453D01*
X71369Y635558D01*
X71453Y635685D01*
X71619D01*
X71703Y635558D01*
G01X69453D02*
X69369Y635431D01*
X69203D01*
X69119Y635558D01*
X69203Y635685D01*
X69369D01*
X69453Y635558D01*
G01X71536Y639265D02*
X66536D01*
Y640531D01*
X66786Y641038D01*
X67119Y641418D01*
X67619Y641735D01*
X68203Y641988D01*
X69036Y642051D01*
X69869Y641988D01*
X70453Y641735D01*
X70953Y641418D01*
X71286Y641038D01*
X71536Y640531D01*
Y639265D01*
G01Y644175D02*
X66536Y645758D01*
X71536Y647341D01*
G01X69786Y646771D02*
Y644745D01*
G01X66536Y650858D02*
X66703Y650351D01*
X67119Y649971D01*
X67619Y649718D01*
X68286Y649528D01*
X69036Y649465D01*
X69786Y649528D01*
X70453Y649718D01*
X70953Y649971D01*
X71369Y650351D01*
X71536Y650858D01*
X71369Y651365D01*
X70953Y651745D01*
X70453Y651998D01*
X69786Y652188D01*
X69036Y652251D01*
X68286Y652188D01*
X67619Y651998D01*
X67119Y651745D01*
X66703Y651365D01*
X66536Y650858D01*
G01Y655958D02*
X71536D01*
G01X66536Y654501D02*
Y657415D01*
G01X69453Y659855D02*
X68869Y660298D01*
X68536Y660678D01*
X68369Y661185D01*
X68536Y661628D01*
X68869Y661945D01*
X69369Y662198D01*
X69953Y662261D01*
X70453Y662198D01*
X70953Y661945D01*
X71369Y661565D01*
X71536Y661121D01*
X71369Y660615D01*
X70869Y660171D01*
X70119Y659918D01*
X69286Y659855D01*
X68203Y659981D01*
X67619Y660171D01*
X67036Y660488D01*
X66619Y660931D01*
X66536Y661375D01*
X66703Y661818D01*
X67119Y662135D01*
G01X71536Y664511D02*
X66536D01*
X70703Y666158D01*
X66536Y667805D01*
X71536D01*
G01X66536Y671258D02*
X71536D01*
G01X66536Y669801D02*
Y672715D01*
G01X68869Y676865D02*
X68619Y677118D01*
X68203Y677308D01*
X67619Y677435D01*
X67119Y677308D01*
X66786Y677055D01*
X66536Y676611D01*
Y674901D01*
X71536D01*
Y676991D01*
X71203Y677435D01*
X70703Y677688D01*
X70119Y677815D01*
X69536Y677688D01*
X69036Y677308D01*
X68869Y676865D01*
Y674901D01*
G01X71536Y681458D02*
X71453Y681901D01*
X71203Y682408D01*
X70786Y682725D01*
X70203Y682851D01*
X69619Y682725D01*
X69119Y682345D01*
X68869Y681775D01*
Y681141D01*
X68703Y680761D01*
X68286Y680445D01*
X67703Y680318D01*
X67119Y680508D01*
X66703Y680951D01*
X66536Y681458D01*
X66703Y681965D01*
X67119Y682408D01*
X67703Y682598D01*
X68286Y682471D01*
X68703Y682155D01*
X68869Y681775D01*
Y681141D01*
X69119Y680571D01*
X69619Y680191D01*
X70203Y680065D01*
X70786Y680191D01*
X71203Y680508D01*
X71453Y681015D01*
X71536Y681458D01*
G01Y685165D02*
X66536D01*
Y686431D01*
X66786Y686938D01*
X67119Y687318D01*
X67619Y687635D01*
X68203Y687888D01*
X69036Y687951D01*
X69869Y687888D01*
X70453Y687635D01*
X70953Y687318D01*
X71286Y686938D01*
X71536Y686431D01*
Y685165D01*
G01X66536Y691658D02*
X66703Y691151D01*
X67119Y690771D01*
X67619Y690518D01*
X68286Y690328D01*
X69036Y690265D01*
X69786Y690328D01*
X70453Y690518D01*
X70953Y690771D01*
X71369Y691151D01*
X71536Y691658D01*
X71369Y692165D01*
X70953Y692545D01*
X70453Y692798D01*
X69786Y692988D01*
X69036Y693051D01*
X68286Y692988D01*
X67619Y692798D01*
X67119Y692545D01*
X66703Y692165D01*
X66536Y691658D01*
G01X53735Y849002D02*
Y852102D01*
G01X55345D02*
Y849002D01*
G01Y850552D02*
X53735D01*
G01X56912Y851585D02*
X57142Y851895D01*
X57410Y852050D01*
X57717Y852102D01*
X58100Y851999D01*
X58368Y851740D01*
X58445Y851430D01*
X58407Y851120D01*
X58253Y850862D01*
X57487Y850345D01*
X57142Y849984D01*
X56912Y849467D01*
X56835Y849002D01*
X58445D01*
G01X58587Y897285D02*
X51087D01*
Y899525D01*
X51462Y900272D01*
X52337Y900832D01*
X53337Y901019D01*
X54337Y900832D01*
X55087Y900365D01*
X55462Y899525D01*
Y897285D01*
G01X58587Y904785D02*
X51087D01*
Y907119D01*
X51462Y907865D01*
X51962Y908332D01*
X52962Y908519D01*
X53962Y908332D01*
X54587Y907772D01*
X54962Y907119D01*
Y904785D01*
G01Y907119D02*
X58587Y908519D01*
G01Y916019D02*
Y912285D01*
X51087D01*
Y916019D01*
G01X54712Y914525D02*
Y912285D01*
G01X57587Y919692D02*
X58212Y920439D01*
X58587Y921279D01*
Y922025D01*
X58212Y922772D01*
X57587Y923332D01*
X56712Y923612D01*
X55837Y923425D01*
X55087Y922959D01*
X54587Y922119D01*
X54337Y920999D01*
X53837Y920345D01*
X52962Y920065D01*
X52087Y920252D01*
X51462Y920719D01*
X51087Y921372D01*
Y922025D01*
X51337Y922679D01*
X51962Y923239D01*
G01X57587Y927192D02*
X58212Y927939D01*
X58587Y928779D01*
Y929525D01*
X58212Y930272D01*
X57587Y930832D01*
X56712Y931112D01*
X55837Y930925D01*
X55087Y930459D01*
X54587Y929619D01*
X54337Y928499D01*
X53837Y927845D01*
X52962Y927565D01*
X52087Y927752D01*
X51462Y928219D01*
X51087Y928872D01*
Y929525D01*
X51337Y930179D01*
X51962Y930739D01*
G01X58587Y949879D02*
X51087D01*
Y953425D01*
G01X54712Y952119D02*
Y949879D01*
G01X51087Y958032D02*
Y960272D01*
G01Y959152D02*
X58587D01*
G01Y958032D02*
Y960272D01*
G01X51087Y966652D02*
X58587D01*
G01X51087Y964505D02*
Y968799D01*
G01X52387Y995165D02*
X52697Y995357D01*
X52904Y995587D01*
X53007Y995855D01*
X52904Y996162D01*
X52697Y996392D01*
X52387Y996622D01*
X51974Y996699D01*
X49907D01*
G01X50424Y998304D02*
X50114Y998534D01*
X49959Y998802D01*
X49907Y999109D01*
X50010Y999492D01*
X50269Y999760D01*
X50579Y999837D01*
X50889Y999799D01*
X51147Y999645D01*
X51664Y998879D01*
X52025Y998534D01*
X52542Y998304D01*
X53007Y998227D01*
Y999837D01*
G01X51715Y1001404D02*
X51354Y1001672D01*
X51147Y1001902D01*
X51044Y1002209D01*
X51147Y1002477D01*
X51354Y1002669D01*
X51664Y1002822D01*
X52025Y1002860D01*
X52335Y1002822D01*
X52645Y1002669D01*
X52904Y1002439D01*
X53007Y1002170D01*
X52904Y1001864D01*
X52594Y1001595D01*
X52129Y1001442D01*
X51612Y1001404D01*
X50940Y1001480D01*
X50579Y1001595D01*
X50217Y1001787D01*
X49959Y1002055D01*
X49907Y1002324D01*
X50010Y1002592D01*
X50269Y1002784D01*
G01X73184Y1053437D02*
X70084Y1054395D01*
X73184Y1055353D01*
G01X72099Y1055008D02*
Y1053782D01*
G01X73184Y1057495D02*
X73132Y1057763D01*
X72977Y1058070D01*
X72719Y1058262D01*
X72357Y1058338D01*
X71996Y1058262D01*
X71686Y1058032D01*
X71531Y1057687D01*
Y1057303D01*
X71427Y1057073D01*
X71169Y1056882D01*
X70807Y1056805D01*
X70446Y1056920D01*
X70187Y1057188D01*
X70084Y1057495D01*
X70187Y1057802D01*
X70446Y1058070D01*
X70807Y1058185D01*
X71169Y1058108D01*
X71427Y1057917D01*
X71531Y1057687D01*
Y1057303D01*
X71686Y1056958D01*
X71996Y1056728D01*
X72357Y1056652D01*
X72719Y1056728D01*
X72977Y1056920D01*
X73132Y1057227D01*
X73184Y1057495D01*
G01X70601Y1059867D02*
X70291Y1060097D01*
X70136Y1060365D01*
X70084Y1060672D01*
X70187Y1061055D01*
X70446Y1061323D01*
X70756Y1061400D01*
X71066Y1061362D01*
X71324Y1061208D01*
X71841Y1060442D01*
X72202Y1060097D01*
X72719Y1059867D01*
X73184Y1059790D01*
Y1061400D01*
G01X59925Y1200573D02*
Y1203673D01*
G01X61535D02*
Y1200573D01*
G01Y1202123D02*
X59925D01*
G01X64290Y1200573D02*
Y1203673D01*
X62872Y1201451D01*
X64788D01*
G01X60031Y1251407D02*
Y1254507D01*
X60990D01*
X61296Y1254352D01*
X61488Y1254145D01*
X61565Y1253732D01*
X61488Y1253319D01*
X61258Y1253060D01*
X60990Y1252905D01*
X60031D01*
G01X60990D02*
X61565Y1251407D01*
G01X63898D02*
Y1254507D01*
X63438Y1253887D01*
G01Y1251407D02*
X64358D01*
G01X67458D02*
Y1254507D01*
X66040Y1252285D01*
X67956D01*
G01X70098Y1254507D02*
X69791Y1254404D01*
X69561Y1254145D01*
X69408Y1253835D01*
X69293Y1253422D01*
X69255Y1252957D01*
X69293Y1252492D01*
X69408Y1252079D01*
X69561Y1251769D01*
X69791Y1251510D01*
X70098Y1251407D01*
X70405Y1251510D01*
X70635Y1251769D01*
X70788Y1252079D01*
X70903Y1252492D01*
X70941Y1252957D01*
X70903Y1253422D01*
X70788Y1253835D01*
X70635Y1254145D01*
X70405Y1254404D01*
X70098Y1254507D01*
G01X55938Y1251778D02*
X49738D01*
Y1254978D01*
X55938D01*
Y1251778D01*
G01X57663Y1261012D02*
Y1264112D01*
X58622D01*
X58928Y1263957D01*
X59120Y1263750D01*
X59197Y1263337D01*
X59120Y1262924D01*
X58890Y1262665D01*
X58622Y1262510D01*
X57663D01*
G01X58622D02*
X59197Y1261012D01*
G01X61530D02*
Y1264112D01*
X61070Y1263492D01*
G01Y1261012D02*
X61990D01*
G01X65090D02*
Y1264112D01*
X63672Y1261890D01*
X65588D01*
G01X68190Y1261012D02*
Y1264112D01*
X66772Y1261890D01*
X68688D01*
G01X55735Y1261503D02*
X49535D01*
Y1264703D01*
X55735D01*
Y1261503D01*
G01X57860Y1255881D02*
Y1258981D01*
X58819D01*
X59125Y1258826D01*
X59317Y1258619D01*
X59394Y1258206D01*
X59317Y1257793D01*
X59087Y1257534D01*
X58819Y1257379D01*
X57860D01*
G01X58819D02*
X59394Y1255881D01*
G01X61727D02*
Y1258981D01*
X61267Y1258361D01*
G01Y1255881D02*
X62187D01*
G01X65287D02*
Y1258981D01*
X63869Y1256759D01*
X65785D01*
G01X67927Y1255881D02*
Y1258981D01*
X67467Y1258361D01*
G01Y1255881D02*
X68387D01*
G01X55802Y1256033D02*
X49602D01*
Y1259233D01*
X55802D01*
Y1256033D01*
G01X57661Y1278387D02*
Y1281487D01*
X58620D01*
X58926Y1281332D01*
X59118Y1281125D01*
X59195Y1280712D01*
X59118Y1280299D01*
X58888Y1280040D01*
X58620Y1279885D01*
X57661D01*
G01X58620D02*
X59195Y1278387D01*
G01X61528D02*
Y1281487D01*
X61068Y1280867D01*
G01Y1278387D02*
X61988D01*
G01X65088D02*
Y1281487D01*
X63670Y1279265D01*
X65586D01*
G01X67000Y1280970D02*
X67230Y1281280D01*
X67498Y1281435D01*
X67805Y1281487D01*
X68188Y1281384D01*
X68456Y1281125D01*
X68533Y1280815D01*
X68495Y1280505D01*
X68341Y1280247D01*
X67575Y1279730D01*
X67230Y1279369D01*
X67000Y1278852D01*
X66923Y1278387D01*
X68533D01*
G01X56107Y1278183D02*
X49907D01*
Y1281383D01*
X56107D01*
Y1278183D01*
G01X57860Y1265683D02*
Y1268783D01*
X58819D01*
X59125Y1268628D01*
X59317Y1268421D01*
X59394Y1268008D01*
X59317Y1267595D01*
X59087Y1267336D01*
X58819Y1267181D01*
X57860D01*
G01X58819D02*
X59394Y1265683D01*
G01X61727D02*
Y1268783D01*
X61267Y1268163D01*
G01Y1265683D02*
X62187D01*
G01X65287D02*
Y1268783D01*
X63869Y1266561D01*
X65785D01*
G01X67084Y1266303D02*
X67314Y1265941D01*
X67620Y1265735D01*
X67965Y1265683D01*
X68272Y1265735D01*
X68579Y1265993D01*
X68770Y1266303D01*
X68809Y1266613D01*
X68732Y1266975D01*
X68464Y1267233D01*
X68195Y1267336D01*
X67850D01*
G01X68195D02*
X68425Y1267491D01*
X68617Y1267750D01*
X68694Y1268060D01*
X68617Y1268370D01*
X68425Y1268628D01*
X68080Y1268783D01*
X67735Y1268731D01*
X67390Y1268525D01*
G01X56073Y1265690D02*
X49873D01*
Y1268890D01*
X56073D01*
Y1265690D01*
G01X57916Y1282477D02*
Y1285577D01*
X58875D01*
X59181Y1285422D01*
X59373Y1285215D01*
X59450Y1284802D01*
X59373Y1284389D01*
X59143Y1284130D01*
X58875Y1283975D01*
X57916D01*
G01X58875D02*
X59450Y1282477D01*
G01X61783D02*
Y1285577D01*
X61323Y1284957D01*
G01Y1282477D02*
X62243D01*
G01X65343D02*
Y1285577D01*
X63925Y1283355D01*
X65841D01*
G01X67140Y1282942D02*
X67370Y1282684D01*
X67638Y1282529D01*
X67983Y1282477D01*
X68328Y1282580D01*
X68596Y1282787D01*
X68788Y1283149D01*
X68826Y1283562D01*
X68750Y1283975D01*
X68558Y1284234D01*
X68290Y1284440D01*
X68021Y1284492D01*
X67753Y1284440D01*
X67408Y1284234D01*
X67523Y1285577D01*
X68558D01*
G01X55971Y1282438D02*
X49771D01*
Y1285638D01*
X55971D01*
Y1282438D01*
G01X57464Y1274242D02*
Y1277342D01*
X58423D01*
X58729Y1277187D01*
X58921Y1276980D01*
X58998Y1276567D01*
X58921Y1276154D01*
X58691Y1275895D01*
X58423Y1275740D01*
X57464D01*
G01X58423D02*
X58998Y1274242D01*
G01X61331D02*
Y1277342D01*
X60871Y1276722D01*
G01Y1274242D02*
X61791D01*
G01X64891D02*
Y1277342D01*
X63473Y1275120D01*
X65389D01*
G01X66803Y1275534D02*
X67071Y1275895D01*
X67301Y1276102D01*
X67608Y1276205D01*
X67876Y1276102D01*
X68068Y1275895D01*
X68221Y1275585D01*
X68259Y1275224D01*
X68221Y1274914D01*
X68068Y1274604D01*
X67838Y1274345D01*
X67569Y1274242D01*
X67263Y1274345D01*
X66994Y1274655D01*
X66841Y1275120D01*
X66803Y1275637D01*
X66879Y1276309D01*
X66994Y1276670D01*
X67186Y1277032D01*
X67454Y1277290D01*
X67723Y1277342D01*
X67991Y1277239D01*
X68183Y1276980D01*
G01X56107Y1274030D02*
X49907D01*
Y1277230D01*
X56107D01*
Y1274030D01*
G01X57597Y1269893D02*
Y1272993D01*
X58556D01*
X58862Y1272838D01*
X59054Y1272631D01*
X59131Y1272218D01*
X59054Y1271805D01*
X58824Y1271546D01*
X58556Y1271391D01*
X57597D01*
G01X58556D02*
X59131Y1269893D01*
G01X61464D02*
Y1272993D01*
X61004Y1272373D01*
G01Y1269893D02*
X61924D01*
G01X65024D02*
Y1272993D01*
X63606Y1270771D01*
X65522D01*
G01X67587Y1269893D02*
X67664Y1270565D01*
X67779Y1271133D01*
X67932Y1271650D01*
X68124Y1272218D01*
X68431Y1272993D01*
X66897D01*
G01X56006Y1269944D02*
X49806D01*
Y1273144D01*
X56006D01*
Y1269944D01*
G01X61069Y1287046D02*
X57969D01*
Y1288005D01*
X58124Y1288311D01*
X58331Y1288503D01*
X58744Y1288580D01*
X59157Y1288503D01*
X59416Y1288273D01*
X59571Y1288005D01*
Y1287046D01*
G01Y1288005D02*
X61069Y1288580D01*
G01X60449Y1290070D02*
X60811Y1290300D01*
X61017Y1290606D01*
X61069Y1290951D01*
X61017Y1291258D01*
X60759Y1291565D01*
X60449Y1291756D01*
X60139Y1291795D01*
X59777Y1291718D01*
X59519Y1291450D01*
X59416Y1291181D01*
Y1290836D01*
G01Y1291181D02*
X59261Y1291411D01*
X59002Y1291603D01*
X58692Y1291680D01*
X58382Y1291603D01*
X58124Y1291411D01*
X57969Y1291066D01*
X58021Y1290721D01*
X58227Y1290376D01*
G01X60604Y1293170D02*
X60862Y1293400D01*
X61017Y1293668D01*
X61069Y1294013D01*
X60966Y1294358D01*
X60759Y1294626D01*
X60397Y1294818D01*
X59984Y1294856D01*
X59571Y1294780D01*
X59312Y1294588D01*
X59106Y1294320D01*
X59054Y1294051D01*
X59106Y1293783D01*
X59312Y1293438D01*
X57969Y1293553D01*
Y1294588D01*
G01X74226Y1286880D02*
X71126D01*
Y1287839D01*
X71281Y1288145D01*
X71488Y1288337D01*
X71901Y1288414D01*
X72314Y1288337D01*
X72573Y1288107D01*
X72728Y1287839D01*
Y1286880D01*
G01Y1287839D02*
X74226Y1288414D01*
G01X73606Y1289904D02*
X73968Y1290134D01*
X74174Y1290440D01*
X74226Y1290785D01*
X74174Y1291092D01*
X73916Y1291399D01*
X73606Y1291590D01*
X73296Y1291629D01*
X72934Y1291552D01*
X72676Y1291284D01*
X72573Y1291015D01*
Y1290670D01*
G01Y1291015D02*
X72418Y1291245D01*
X72159Y1291437D01*
X71849Y1291514D01*
X71539Y1291437D01*
X71281Y1291245D01*
X71126Y1290900D01*
X71178Y1290555D01*
X71384Y1290210D01*
G01X72934Y1293119D02*
X72573Y1293387D01*
X72366Y1293617D01*
X72263Y1293924D01*
X72366Y1294192D01*
X72573Y1294384D01*
X72883Y1294537D01*
X73244Y1294575D01*
X73554Y1294537D01*
X73864Y1294384D01*
X74123Y1294154D01*
X74226Y1293885D01*
X74123Y1293579D01*
X73813Y1293310D01*
X73348Y1293157D01*
X72831Y1293119D01*
X72159Y1293195D01*
X71798Y1293310D01*
X71436Y1293502D01*
X71178Y1293770D01*
X71126Y1294039D01*
X71229Y1294307D01*
X71488Y1294499D01*
G01X52648Y1286980D02*
X49548D01*
Y1287939D01*
X49703Y1288245D01*
X49910Y1288437D01*
X50323Y1288514D01*
X50736Y1288437D01*
X50995Y1288207D01*
X51150Y1287939D01*
Y1286980D01*
G01Y1287939D02*
X52648Y1288514D01*
G01X52028Y1290004D02*
X52390Y1290234D01*
X52596Y1290540D01*
X52648Y1290885D01*
X52596Y1291192D01*
X52338Y1291499D01*
X52028Y1291690D01*
X51718Y1291729D01*
X51356Y1291652D01*
X51098Y1291384D01*
X50995Y1291115D01*
Y1290770D01*
G01Y1291115D02*
X50840Y1291345D01*
X50581Y1291537D01*
X50271Y1291614D01*
X49961Y1291537D01*
X49703Y1291345D01*
X49548Y1291000D01*
X49600Y1290655D01*
X49806Y1290310D01*
G01X52648Y1294407D02*
X49548D01*
X51770Y1292989D01*
Y1294905D01*
G01X56860Y1286981D02*
X53760D01*
Y1287940D01*
X53915Y1288246D01*
X54122Y1288438D01*
X54535Y1288515D01*
X54948Y1288438D01*
X55207Y1288208D01*
X55362Y1287940D01*
Y1286981D01*
G01Y1287940D02*
X56860Y1288515D01*
G01X56240Y1290005D02*
X56602Y1290235D01*
X56808Y1290541D01*
X56860Y1290886D01*
X56808Y1291193D01*
X56550Y1291500D01*
X56240Y1291691D01*
X55930Y1291730D01*
X55568Y1291653D01*
X55310Y1291385D01*
X55207Y1291116D01*
Y1290771D01*
G01Y1291116D02*
X55052Y1291346D01*
X54793Y1291538D01*
X54483Y1291615D01*
X54173Y1291538D01*
X53915Y1291346D01*
X53760Y1291001D01*
X53812Y1290656D01*
X54018Y1290311D01*
G01X56860Y1293871D02*
X56188Y1293948D01*
X55620Y1294063D01*
X55103Y1294216D01*
X54535Y1294408D01*
X53760Y1294715D01*
Y1293181D01*
G01X65378Y1287046D02*
X62278D01*
Y1288005D01*
X62433Y1288311D01*
X62640Y1288503D01*
X63053Y1288580D01*
X63466Y1288503D01*
X63725Y1288273D01*
X63880Y1288005D01*
Y1287046D01*
G01Y1288005D02*
X65378Y1288580D01*
G01X64758Y1290070D02*
X65120Y1290300D01*
X65326Y1290606D01*
X65378Y1290951D01*
X65326Y1291258D01*
X65068Y1291565D01*
X64758Y1291756D01*
X64448Y1291795D01*
X64086Y1291718D01*
X63828Y1291450D01*
X63725Y1291181D01*
Y1290836D01*
G01Y1291181D02*
X63570Y1291411D01*
X63311Y1291603D01*
X63001Y1291680D01*
X62691Y1291603D01*
X62433Y1291411D01*
X62278Y1291066D01*
X62330Y1290721D01*
X62536Y1290376D01*
G01X65378Y1294013D02*
X65326Y1294281D01*
X65171Y1294588D01*
X64913Y1294780D01*
X64551Y1294856D01*
X64190Y1294780D01*
X63880Y1294550D01*
X63725Y1294205D01*
Y1293821D01*
X63621Y1293591D01*
X63363Y1293400D01*
X63001Y1293323D01*
X62640Y1293438D01*
X62381Y1293706D01*
X62278Y1294013D01*
X62381Y1294320D01*
X62640Y1294588D01*
X63001Y1294703D01*
X63363Y1294626D01*
X63621Y1294435D01*
X63725Y1294205D01*
Y1293821D01*
X63880Y1293476D01*
X64190Y1293246D01*
X64551Y1293170D01*
X64913Y1293246D01*
X65171Y1293438D01*
X65326Y1293745D01*
X65378Y1294013D01*
G01X69885Y1286881D02*
X66785D01*
Y1287840D01*
X66940Y1288146D01*
X67147Y1288338D01*
X67560Y1288415D01*
X67973Y1288338D01*
X68232Y1288108D01*
X68387Y1287840D01*
Y1286881D01*
G01Y1287840D02*
X69885Y1288415D01*
G01X69265Y1289905D02*
X69627Y1290135D01*
X69833Y1290441D01*
X69885Y1290786D01*
X69833Y1291093D01*
X69575Y1291400D01*
X69265Y1291591D01*
X68955Y1291630D01*
X68593Y1291553D01*
X68335Y1291285D01*
X68232Y1291016D01*
Y1290671D01*
G01Y1291016D02*
X68077Y1291246D01*
X67818Y1291438D01*
X67508Y1291515D01*
X67198Y1291438D01*
X66940Y1291246D01*
X66785Y1290901D01*
X66837Y1290556D01*
X67043Y1290211D01*
G01X69523Y1293196D02*
X69782Y1293465D01*
X69885Y1293771D01*
X69782Y1294078D01*
X69472Y1294346D01*
X69007Y1294538D01*
X68542Y1294615D01*
X67973D01*
X67508Y1294538D01*
X67095Y1294346D01*
X66888Y1294116D01*
X66785Y1293848D01*
X66888Y1293541D01*
X67095Y1293311D01*
X67405Y1293158D01*
X67818Y1293081D01*
X68180Y1293158D01*
X68542Y1293350D01*
X68748Y1293580D01*
X68800Y1293848D01*
X68697Y1294155D01*
X68438Y1294385D01*
X67973Y1294615D01*
G01X60352Y1304271D02*
Y1298071D01*
X57152D01*
Y1304271D01*
X60352D01*
G01X73509Y1304105D02*
Y1297905D01*
X70309D01*
Y1304105D01*
X73509D01*
G01X56143Y1304206D02*
Y1298006D01*
X52943D01*
Y1304206D01*
X56143D01*
G01X64661Y1304271D02*
Y1298071D01*
X61461D01*
Y1304271D01*
X64661D01*
G01X69168Y1304106D02*
Y1297906D01*
X65968D01*
Y1304106D01*
X69168D01*
G01X54558Y1340756D02*
Y1334556D01*
X51358D01*
Y1340756D01*
X54558D01*
G01X57866Y1322203D02*
G03I-1000J0D01*
G01X54466Y1331303D02*
X74266D01*
Y1320103D01*
X54466D01*
Y1323903D01*
X56266Y1325703D01*
X54466Y1327503D01*
Y1331303D01*
G01X55137Y1343345D02*
X52037D01*
Y1344304D01*
X52192Y1344610D01*
X52399Y1344802D01*
X52812Y1344879D01*
X53225Y1344802D01*
X53484Y1344572D01*
X53639Y1344304D01*
Y1343345D01*
G01Y1344304D02*
X55137Y1344879D01*
G01Y1347672D02*
X52037D01*
X54259Y1346254D01*
Y1348170D01*
G01X55137Y1350312D02*
X52037D01*
X52657Y1349852D01*
G01X55137D02*
Y1350772D01*
G01X66828Y1366381D02*
X61828D01*
Y1367901D01*
X62078Y1368408D01*
X62661Y1368788D01*
X63328Y1368915D01*
X63995Y1368788D01*
X64495Y1368471D01*
X64745Y1367901D01*
Y1366381D01*
G01X66828Y1371481D02*
X61828D01*
Y1373065D01*
X62078Y1373571D01*
X62411Y1373888D01*
X63078Y1374015D01*
X63745Y1373888D01*
X64161Y1373508D01*
X64411Y1373065D01*
Y1371481D01*
G01Y1373065D02*
X66828Y1374015D01*
G01Y1379115D02*
Y1376581D01*
X61828D01*
Y1379115D01*
G01X64245Y1378101D02*
Y1376581D01*
G01X66161Y1381618D02*
X66578Y1382125D01*
X66828Y1382695D01*
Y1383201D01*
X66578Y1383708D01*
X66161Y1384088D01*
X65578Y1384278D01*
X64995Y1384151D01*
X64495Y1383835D01*
X64161Y1383265D01*
X63995Y1382505D01*
X63661Y1382061D01*
X63078Y1381871D01*
X62495Y1381998D01*
X62078Y1382315D01*
X61828Y1382758D01*
Y1383201D01*
X61995Y1383645D01*
X62411Y1384025D01*
G01X66161Y1386718D02*
X66578Y1387225D01*
X66828Y1387795D01*
Y1388301D01*
X66578Y1388808D01*
X66161Y1389188D01*
X65578Y1389378D01*
X64995Y1389251D01*
X64495Y1388935D01*
X64161Y1388365D01*
X63995Y1387605D01*
X63661Y1387161D01*
X63078Y1386971D01*
X62495Y1387098D01*
X62078Y1387415D01*
X61828Y1387858D01*
Y1388301D01*
X61995Y1388745D01*
X62411Y1389125D01*
G01X66828Y1402145D02*
X61828D01*
Y1404551D01*
G01X64245Y1403665D02*
Y1402145D01*
G01X61828Y1407688D02*
Y1409208D01*
G01Y1408448D02*
X66828D01*
G01Y1407688D02*
Y1409208D01*
G01X61828Y1413548D02*
X66828D01*
G01X61828Y1412091D02*
Y1415005D01*
G01X52364Y1381707D02*
X52674Y1381899D01*
X52881Y1382129D01*
X52984Y1382397D01*
X52881Y1382704D01*
X52674Y1382934D01*
X52364Y1383164D01*
X51951Y1383241D01*
X49884D01*
G01X50401Y1384846D02*
X50091Y1385076D01*
X49936Y1385344D01*
X49884Y1385651D01*
X49987Y1386034D01*
X50246Y1386302D01*
X50556Y1386379D01*
X50866Y1386341D01*
X51124Y1386187D01*
X51641Y1385421D01*
X52002Y1385076D01*
X52519Y1384846D01*
X52984Y1384769D01*
Y1386379D01*
G01X52519Y1387831D02*
X52777Y1388061D01*
X52932Y1388329D01*
X52984Y1388674D01*
X52881Y1389019D01*
X52674Y1389287D01*
X52312Y1389479D01*
X51899Y1389517D01*
X51486Y1389441D01*
X51227Y1389249D01*
X51021Y1388981D01*
X50969Y1388712D01*
X51021Y1388444D01*
X51227Y1388099D01*
X49884Y1388214D01*
Y1389249D01*
G01X65229Y1556882D02*
Y1559982D01*
X66188D01*
X66494Y1559827D01*
X66686Y1559620D01*
X66763Y1559207D01*
X66686Y1558794D01*
X66456Y1558535D01*
X66188Y1558380D01*
X65229D01*
G01X66188D02*
X66763Y1556882D01*
G01X69096D02*
Y1559982D01*
X68636Y1559362D01*
G01Y1556882D02*
X69556D01*
G01X71353Y1557347D02*
X71583Y1557089D01*
X71851Y1556934D01*
X72196Y1556882D01*
X72541Y1556985D01*
X72809Y1557192D01*
X73001Y1557554D01*
X73039Y1557967D01*
X72963Y1558380D01*
X72771Y1558639D01*
X72503Y1558845D01*
X72234Y1558897D01*
X71966Y1558845D01*
X71621Y1558639D01*
X71736Y1559982D01*
X72771D01*
G01X74453Y1557502D02*
X74683Y1557140D01*
X74989Y1556934D01*
X75334Y1556882D01*
X75641Y1556934D01*
X75948Y1557192D01*
X76139Y1557502D01*
X76178Y1557812D01*
X76101Y1558174D01*
X75833Y1558432D01*
X75564Y1558535D01*
X75219D01*
G01X75564D02*
X75794Y1558690D01*
X75986Y1558949D01*
X76063Y1559259D01*
X75986Y1559569D01*
X75794Y1559827D01*
X75449Y1559982D01*
X75104Y1559930D01*
X74759Y1559724D01*
G01X62805Y1557538D02*
X56605D01*
Y1560738D01*
X62805D01*
Y1557538D01*
G01X68778Y1598092D02*
Y1562205D01*
G01X71245Y1621809D02*
X71513Y1621861D01*
X71820Y1622016D01*
X72012Y1622274D01*
X72088Y1622636D01*
X72012Y1622997D01*
X71782Y1623307D01*
X71437Y1623462D01*
X71053D01*
X70823Y1623566D01*
X70632Y1623824D01*
X70555Y1624186D01*
X70670Y1624547D01*
X70938Y1624806D01*
X71245Y1624909D01*
X71552Y1624806D01*
X71820Y1624547D01*
X71935Y1624186D01*
X71858Y1623824D01*
X71667Y1623566D01*
X71437Y1623462D01*
X71053D01*
X70708Y1623307D01*
X70478Y1622997D01*
X70402Y1622636D01*
X70478Y1622274D01*
X70670Y1622016D01*
X70977Y1621861D01*
X71245Y1621809D01*
G01X71018Y1611909D02*
X71095Y1612581D01*
X71210Y1613149D01*
X71363Y1613666D01*
X71555Y1614234D01*
X71862Y1615009D01*
X70328D01*
G01X68035Y1955958D02*
X68303Y1956010D01*
X68610Y1956165D01*
X68802Y1956423D01*
X68878Y1956785D01*
X68802Y1957146D01*
X68572Y1957456D01*
X68227Y1957611D01*
X67843D01*
X67613Y1957715D01*
X67422Y1957973D01*
X67345Y1958335D01*
X67460Y1958696D01*
X67728Y1958955D01*
X68035Y1959058D01*
X68342Y1958955D01*
X68610Y1958696D01*
X68725Y1958335D01*
X68648Y1957973D01*
X68457Y1957715D01*
X68227Y1957611D01*
X67843D01*
X67498Y1957456D01*
X67268Y1957146D01*
X67192Y1956785D01*
X67268Y1956423D01*
X67460Y1956165D01*
X67767Y1956010D01*
X68035Y1955958D01*
G01X67958Y1946258D02*
X68035Y1946930D01*
X68150Y1947498D01*
X68303Y1948015D01*
X68495Y1948583D01*
X68802Y1949358D01*
X67268D01*
G01X68035Y2060328D02*
X68303Y2060380D01*
X68610Y2060535D01*
X68802Y2060793D01*
X68878Y2061155D01*
X68802Y2061516D01*
X68572Y2061826D01*
X68227Y2061981D01*
X67843D01*
X67613Y2062085D01*
X67422Y2062343D01*
X67345Y2062705D01*
X67460Y2063066D01*
X67728Y2063325D01*
X68035Y2063428D01*
X68342Y2063325D01*
X68610Y2063066D01*
X68725Y2062705D01*
X68648Y2062343D01*
X68457Y2062085D01*
X68227Y2061981D01*
X67843D01*
X67498Y2061826D01*
X67268Y2061516D01*
X67192Y2061155D01*
X67268Y2060793D01*
X67460Y2060535D01*
X67767Y2060380D01*
X68035Y2060328D01*
G01X67958Y2050628D02*
X68035Y2051300D01*
X68150Y2051868D01*
X68303Y2052385D01*
X68495Y2052953D01*
X68802Y2053728D01*
X67268D01*
G01X87914Y31010D02*
Y34110D01*
X88873D01*
X89179Y33955D01*
X89371Y33748D01*
X89448Y33335D01*
X89371Y32922D01*
X89141Y32663D01*
X88873Y32508D01*
X87914D01*
G01X88873D02*
X89448Y31010D01*
G01X92241D02*
Y34110D01*
X90823Y31888D01*
X92739D01*
G01X94038Y31630D02*
X94268Y31268D01*
X94574Y31062D01*
X94919Y31010D01*
X95226Y31062D01*
X95533Y31320D01*
X95724Y31630D01*
X95763Y31940D01*
X95686Y32302D01*
X95418Y32560D01*
X95149Y32663D01*
X94804D01*
G01X95149D02*
X95379Y32818D01*
X95571Y33077D01*
X95648Y33387D01*
X95571Y33697D01*
X95379Y33955D01*
X95034Y34110D01*
X94689Y34058D01*
X94344Y33852D01*
G01X87914Y26477D02*
Y29577D01*
X88873D01*
X89179Y29422D01*
X89371Y29215D01*
X89448Y28802D01*
X89371Y28389D01*
X89141Y28130D01*
X88873Y27975D01*
X87914D01*
G01X88873D02*
X89448Y26477D01*
G01X91053Y27769D02*
X91321Y28130D01*
X91551Y28337D01*
X91858Y28440D01*
X92126Y28337D01*
X92318Y28130D01*
X92471Y27820D01*
X92509Y27459D01*
X92471Y27149D01*
X92318Y26839D01*
X92088Y26580D01*
X91819Y26477D01*
X91513Y26580D01*
X91244Y26890D01*
X91091Y27355D01*
X91053Y27872D01*
X91129Y28544D01*
X91244Y28905D01*
X91436Y29267D01*
X91704Y29525D01*
X91973Y29577D01*
X92241Y29474D01*
X92433Y29215D01*
G01X94153Y29060D02*
X94383Y29370D01*
X94651Y29525D01*
X94958Y29577D01*
X95341Y29474D01*
X95609Y29215D01*
X95686Y28905D01*
X95648Y28595D01*
X95494Y28337D01*
X94728Y27820D01*
X94383Y27459D01*
X94153Y26942D01*
X94076Y26477D01*
X95686D01*
G01X87829Y22360D02*
Y25460D01*
X88788D01*
X89094Y25305D01*
X89286Y25098D01*
X89363Y24685D01*
X89286Y24272D01*
X89056Y24013D01*
X88788Y23858D01*
X87829D01*
G01X88788D02*
X89363Y22360D01*
G01X90968Y23652D02*
X91236Y24013D01*
X91466Y24220D01*
X91773Y24323D01*
X92041Y24220D01*
X92233Y24013D01*
X92386Y23703D01*
X92424Y23342D01*
X92386Y23032D01*
X92233Y22722D01*
X92003Y22463D01*
X91734Y22360D01*
X91428Y22463D01*
X91159Y22773D01*
X91006Y23238D01*
X90968Y23755D01*
X91044Y24427D01*
X91159Y24788D01*
X91351Y25150D01*
X91619Y25408D01*
X91888Y25460D01*
X92156Y25357D01*
X92348Y25098D01*
G01X95256Y22360D02*
Y25460D01*
X93838Y23238D01*
X95754D01*
G01X91259Y45559D02*
Y48659D01*
X92218D01*
X92524Y48504D01*
X92716Y48297D01*
X92793Y47884D01*
X92716Y47471D01*
X92486Y47212D01*
X92218Y47057D01*
X91259D01*
G01X92218D02*
X92793Y45559D01*
G01X95586D02*
Y48659D01*
X94168Y46437D01*
X96084D01*
G01X97574Y45921D02*
X97843Y45662D01*
X98149Y45559D01*
X98456Y45662D01*
X98724Y45972D01*
X98916Y46437D01*
X98993Y46902D01*
Y47471D01*
X98916Y47936D01*
X98724Y48349D01*
X98494Y48556D01*
X98226Y48659D01*
X97919Y48556D01*
X97689Y48349D01*
X97536Y48039D01*
X97459Y47626D01*
X97536Y47264D01*
X97728Y46902D01*
X97958Y46696D01*
X98226Y46644D01*
X98533Y46747D01*
X98763Y47006D01*
X98993Y47471D01*
G01X91062Y41678D02*
Y44778D01*
X92021D01*
X92327Y44623D01*
X92519Y44416D01*
X92596Y44003D01*
X92519Y43590D01*
X92289Y43331D01*
X92021Y43176D01*
X91062D01*
G01X92021D02*
X92596Y41678D01*
G01X94086Y42143D02*
X94316Y41885D01*
X94584Y41730D01*
X94929Y41678D01*
X95274Y41781D01*
X95542Y41988D01*
X95734Y42350D01*
X95772Y42763D01*
X95696Y43176D01*
X95504Y43435D01*
X95236Y43641D01*
X94967Y43693D01*
X94699Y43641D01*
X94354Y43435D01*
X94469Y44778D01*
X95504D01*
G01X98029D02*
X97722Y44675D01*
X97492Y44416D01*
X97339Y44106D01*
X97224Y43693D01*
X97186Y43228D01*
X97224Y42763D01*
X97339Y42350D01*
X97492Y42040D01*
X97722Y41781D01*
X98029Y41678D01*
X98336Y41781D01*
X98566Y42040D01*
X98719Y42350D01*
X98834Y42763D01*
X98872Y43228D01*
X98834Y43693D01*
X98719Y44106D01*
X98566Y44416D01*
X98336Y44675D01*
X98029Y44778D01*
G01X87914Y35595D02*
Y38695D01*
X88873D01*
X89179Y38540D01*
X89371Y38333D01*
X89448Y37920D01*
X89371Y37507D01*
X89141Y37248D01*
X88873Y37093D01*
X87914D01*
G01X88873D02*
X89448Y35595D01*
G01X91053Y36887D02*
X91321Y37248D01*
X91551Y37455D01*
X91858Y37558D01*
X92126Y37455D01*
X92318Y37248D01*
X92471Y36938D01*
X92509Y36577D01*
X92471Y36267D01*
X92318Y35957D01*
X92088Y35698D01*
X91819Y35595D01*
X91513Y35698D01*
X91244Y36008D01*
X91091Y36473D01*
X91053Y36990D01*
X91129Y37662D01*
X91244Y38023D01*
X91436Y38385D01*
X91704Y38643D01*
X91973Y38695D01*
X92241Y38592D01*
X92433Y38333D01*
G01X94038Y36215D02*
X94268Y35853D01*
X94574Y35647D01*
X94919Y35595D01*
X95226Y35647D01*
X95533Y35905D01*
X95724Y36215D01*
X95763Y36525D01*
X95686Y36887D01*
X95418Y37145D01*
X95149Y37248D01*
X94804D01*
G01X95149D02*
X95379Y37403D01*
X95571Y37662D01*
X95648Y37972D01*
X95571Y38282D01*
X95379Y38540D01*
X95034Y38695D01*
X94689Y38643D01*
X94344Y38437D01*
G01X89023Y56874D02*
Y59974D01*
X89982D01*
X90288Y59819D01*
X90480Y59612D01*
X90557Y59199D01*
X90480Y58786D01*
X90250Y58527D01*
X89982Y58372D01*
X89023D01*
G01X89982D02*
X90557Y56874D01*
G01X92890D02*
Y59974D01*
X92430Y59354D01*
G01Y56874D02*
X93350D01*
G01X95147Y57494D02*
X95377Y57132D01*
X95683Y56926D01*
X96028Y56874D01*
X96335Y56926D01*
X96642Y57184D01*
X96833Y57494D01*
X96872Y57804D01*
X96795Y58166D01*
X96527Y58424D01*
X96258Y58527D01*
X95913D01*
G01X96258D02*
X96488Y58682D01*
X96680Y58941D01*
X96757Y59251D01*
X96680Y59561D01*
X96488Y59819D01*
X96143Y59974D01*
X95798Y59922D01*
X95453Y59716D01*
G01X99550Y56874D02*
Y59974D01*
X98132Y57752D01*
X100048D01*
G01X95788Y76606D02*
Y79706D01*
X96747D01*
X97053Y79551D01*
X97245Y79344D01*
X97322Y78931D01*
X97245Y78518D01*
X97015Y78259D01*
X96747Y78104D01*
X95788D01*
G01X96747D02*
X97322Y76606D01*
G01X98812Y77071D02*
X99042Y76813D01*
X99310Y76658D01*
X99655Y76606D01*
X100000Y76709D01*
X100268Y76916D01*
X100460Y77278D01*
X100498Y77691D01*
X100422Y78104D01*
X100230Y78363D01*
X99962Y78569D01*
X99693Y78621D01*
X99425Y78569D01*
X99080Y78363D01*
X99195Y79706D01*
X100230D01*
G01X89484Y140489D02*
Y143589D01*
G01X91094D02*
Y140489D01*
G01Y142039D02*
X89484D01*
G01X93389Y140489D02*
Y143589D01*
X92929Y142969D01*
G01Y140489D02*
X93849D01*
G01X96489D02*
Y143589D01*
X96029Y142969D01*
G01Y140489D02*
X96949D01*
G01X87855Y247225D02*
X87605Y247478D01*
X87189Y247668D01*
X86605Y247795D01*
X86105Y247668D01*
X85772Y247415D01*
X85522Y246971D01*
Y245261D01*
X90522D01*
Y247351D01*
X90189Y247795D01*
X89689Y248048D01*
X89105Y248175D01*
X88522Y248048D01*
X88022Y247668D01*
X87855Y247225D01*
Y245261D01*
G01X90522Y252958D02*
X87189D01*
G01X87772D02*
X87439Y252705D01*
X87272Y252325D01*
X87189Y251881D01*
X87355Y251438D01*
X87689Y251058D01*
X88189Y250805D01*
X88855Y250678D01*
X89522Y250805D01*
X90022Y251058D01*
X90355Y251438D01*
X90522Y251881D01*
X90439Y252325D01*
X90189Y252705D01*
X89855Y252958D01*
G01X90522Y256031D02*
X87189D01*
G01X87855D02*
X87522Y256348D01*
X87272Y256665D01*
X87189Y257108D01*
X87272Y257425D01*
X87522Y257805D01*
G01X87605Y263031D02*
X87272Y262588D01*
X87189Y262208D01*
X87355Y261701D01*
X87689Y261321D01*
X88272Y261068D01*
X88855Y261005D01*
X89439Y261068D01*
X89939Y261321D01*
X90355Y261701D01*
X90522Y262208D01*
X90355Y262651D01*
X90022Y263031D01*
G01X90522Y267118D02*
X90439Y266738D01*
X90105Y266358D01*
X89522Y266105D01*
X88855Y265978D01*
X88189Y266105D01*
X87605Y266358D01*
X87272Y266738D01*
X87189Y267118D01*
X87272Y267498D01*
X87605Y267878D01*
X88189Y268131D01*
X88855Y268195D01*
X89522Y268131D01*
X90105Y267878D01*
X90439Y267498D01*
X90522Y267118D01*
G01X85522Y273358D02*
X90522D01*
G01X89772D02*
X90189Y273105D01*
X90439Y272725D01*
X90522Y272281D01*
X90355Y271775D01*
X89939Y271395D01*
X89439Y271141D01*
X88855Y271078D01*
X88272Y271141D01*
X87772Y271395D01*
X87355Y271775D01*
X87189Y272281D01*
X87272Y272725D01*
X87439Y273041D01*
X87772Y273358D01*
G01X88272Y276368D02*
Y278395D01*
X87689Y278205D01*
X87355Y277888D01*
X87189Y277445D01*
X87272Y277001D01*
X87522Y276621D01*
X88105Y276368D01*
X88605Y276241D01*
X89105D01*
X89605Y276368D01*
X90105Y276685D01*
X90439Y277065D01*
X90522Y277508D01*
X90355Y277951D01*
X89855Y278395D01*
G01X86412Y370812D02*
Y373912D01*
X87371D01*
X87677Y373757D01*
X87869Y373550D01*
X87946Y373137D01*
X87869Y372724D01*
X87639Y372465D01*
X87371Y372310D01*
X86412D01*
G01X87371D02*
X87946Y370812D01*
G01X89551Y372104D02*
X89819Y372465D01*
X90049Y372672D01*
X90356Y372775D01*
X90624Y372672D01*
X90816Y372465D01*
X90969Y372155D01*
X91007Y371794D01*
X90969Y371484D01*
X90816Y371174D01*
X90586Y370915D01*
X90317Y370812D01*
X90011Y370915D01*
X89742Y371225D01*
X89589Y371690D01*
X89551Y372207D01*
X89627Y372879D01*
X89742Y373240D01*
X89934Y373602D01*
X90202Y373860D01*
X90471Y373912D01*
X90739Y373809D01*
X90931Y373550D01*
G01X92727Y371174D02*
X92996Y370915D01*
X93302Y370812D01*
X93609Y370915D01*
X93877Y371225D01*
X94069Y371690D01*
X94146Y372155D01*
Y372724D01*
X94069Y373189D01*
X93877Y373602D01*
X93647Y373809D01*
X93379Y373912D01*
X93072Y373809D01*
X92842Y373602D01*
X92689Y373292D01*
X92612Y372879D01*
X92689Y372517D01*
X92881Y372155D01*
X93111Y371949D01*
X93379Y371897D01*
X93686Y372000D01*
X93916Y372259D01*
X94146Y372724D01*
G01X86412Y390123D02*
Y393223D01*
X87371D01*
X87677Y393068D01*
X87869Y392861D01*
X87946Y392448D01*
X87869Y392035D01*
X87639Y391776D01*
X87371Y391621D01*
X86412D01*
G01X87371D02*
X87946Y390123D01*
G01X90739D02*
Y393223D01*
X89321Y391001D01*
X91237D01*
G01X92651Y391415D02*
X92919Y391776D01*
X93149Y391983D01*
X93456Y392086D01*
X93724Y391983D01*
X93916Y391776D01*
X94069Y391466D01*
X94107Y391105D01*
X94069Y390795D01*
X93916Y390485D01*
X93686Y390226D01*
X93417Y390123D01*
X93111Y390226D01*
X92842Y390536D01*
X92689Y391001D01*
X92651Y391518D01*
X92727Y392190D01*
X92842Y392551D01*
X93034Y392913D01*
X93302Y393171D01*
X93571Y393223D01*
X93839Y393120D01*
X94031Y392861D01*
G01X86412Y375483D02*
Y378583D01*
X87371D01*
X87677Y378428D01*
X87869Y378221D01*
X87946Y377808D01*
X87869Y377395D01*
X87639Y377136D01*
X87371Y376981D01*
X86412D01*
G01X87371D02*
X87946Y375483D01*
G01X90739D02*
Y378583D01*
X89321Y376361D01*
X91237D01*
G01X93302Y375483D02*
X93379Y376155D01*
X93494Y376723D01*
X93647Y377240D01*
X93839Y377808D01*
X94146Y378583D01*
X92612D01*
G01X86412Y385138D02*
Y388238D01*
X87371D01*
X87677Y388083D01*
X87869Y387876D01*
X87946Y387463D01*
X87869Y387050D01*
X87639Y386791D01*
X87371Y386636D01*
X86412D01*
G01X87371D02*
X87946Y385138D01*
G01X89551Y386430D02*
X89819Y386791D01*
X90049Y386998D01*
X90356Y387101D01*
X90624Y386998D01*
X90816Y386791D01*
X90969Y386481D01*
X91007Y386120D01*
X90969Y385810D01*
X90816Y385500D01*
X90586Y385241D01*
X90317Y385138D01*
X90011Y385241D01*
X89742Y385551D01*
X89589Y386016D01*
X89551Y386533D01*
X89627Y387205D01*
X89742Y387566D01*
X89934Y387928D01*
X90202Y388186D01*
X90471Y388238D01*
X90739Y388135D01*
X90931Y387876D01*
G01X92651Y386430D02*
X92919Y386791D01*
X93149Y386998D01*
X93456Y387101D01*
X93724Y386998D01*
X93916Y386791D01*
X94069Y386481D01*
X94107Y386120D01*
X94069Y385810D01*
X93916Y385500D01*
X93686Y385241D01*
X93417Y385138D01*
X93111Y385241D01*
X92842Y385551D01*
X92689Y386016D01*
X92651Y386533D01*
X92727Y387205D01*
X92842Y387566D01*
X93034Y387928D01*
X93302Y388186D01*
X93571Y388238D01*
X93839Y388135D01*
X94031Y387876D01*
G01X86412Y380289D02*
Y383389D01*
X87371D01*
X87677Y383234D01*
X87869Y383027D01*
X87946Y382614D01*
X87869Y382201D01*
X87639Y381942D01*
X87371Y381787D01*
X86412D01*
G01X87371D02*
X87946Y380289D01*
G01X89551Y381581D02*
X89819Y381942D01*
X90049Y382149D01*
X90356Y382252D01*
X90624Y382149D01*
X90816Y381942D01*
X90969Y381632D01*
X91007Y381271D01*
X90969Y380961D01*
X90816Y380651D01*
X90586Y380392D01*
X90317Y380289D01*
X90011Y380392D01*
X89742Y380702D01*
X89589Y381167D01*
X89551Y381684D01*
X89627Y382356D01*
X89742Y382717D01*
X89934Y383079D01*
X90202Y383337D01*
X90471Y383389D01*
X90739Y383286D01*
X90931Y383027D01*
G01X93379Y380289D02*
X93647Y380341D01*
X93954Y380496D01*
X94146Y380754D01*
X94222Y381116D01*
X94146Y381477D01*
X93916Y381787D01*
X93571Y381942D01*
X93187D01*
X92957Y382046D01*
X92766Y382304D01*
X92689Y382666D01*
X92804Y383027D01*
X93072Y383286D01*
X93379Y383389D01*
X93686Y383286D01*
X93954Y383027D01*
X94069Y382666D01*
X93992Y382304D01*
X93801Y382046D01*
X93571Y381942D01*
X93187D01*
X92842Y381787D01*
X92612Y381477D01*
X92536Y381116D01*
X92612Y380754D01*
X92804Y380496D01*
X93111Y380341D01*
X93379Y380289D01*
G01X86412Y394927D02*
Y398027D01*
X87371D01*
X87677Y397872D01*
X87869Y397665D01*
X87946Y397252D01*
X87869Y396839D01*
X87639Y396580D01*
X87371Y396425D01*
X86412D01*
G01X87371D02*
X87946Y394927D01*
G01X89551Y396219D02*
X89819Y396580D01*
X90049Y396787D01*
X90356Y396890D01*
X90624Y396787D01*
X90816Y396580D01*
X90969Y396270D01*
X91007Y395909D01*
X90969Y395599D01*
X90816Y395289D01*
X90586Y395030D01*
X90317Y394927D01*
X90011Y395030D01*
X89742Y395340D01*
X89589Y395805D01*
X89551Y396322D01*
X89627Y396994D01*
X89742Y397355D01*
X89934Y397717D01*
X90202Y397975D01*
X90471Y398027D01*
X90739Y397924D01*
X90931Y397665D01*
G01X93302Y394927D02*
X93379Y395599D01*
X93494Y396167D01*
X93647Y396684D01*
X93839Y397252D01*
X94146Y398027D01*
X92612D01*
G01X86280Y399160D02*
Y402260D01*
X87239D01*
X87545Y402105D01*
X87737Y401898D01*
X87814Y401485D01*
X87737Y401072D01*
X87507Y400813D01*
X87239Y400658D01*
X86280D01*
G01X87239D02*
X87814Y399160D01*
G01X90147D02*
Y402260D01*
X89687Y401640D01*
G01Y399160D02*
X90607D01*
G01X92404Y399780D02*
X92634Y399418D01*
X92940Y399212D01*
X93285Y399160D01*
X93592Y399212D01*
X93899Y399470D01*
X94090Y399780D01*
X94129Y400090D01*
X94052Y400452D01*
X93784Y400710D01*
X93515Y400813D01*
X93170D01*
G01X93515D02*
X93745Y400968D01*
X93937Y401227D01*
X94014Y401537D01*
X93937Y401847D01*
X93745Y402105D01*
X93400Y402260D01*
X93055Y402208D01*
X92710Y402002D01*
G01X95504Y399625D02*
X95734Y399367D01*
X96002Y399212D01*
X96347Y399160D01*
X96692Y399263D01*
X96960Y399470D01*
X97152Y399832D01*
X97190Y400245D01*
X97114Y400658D01*
X96922Y400917D01*
X96654Y401123D01*
X96385Y401175D01*
X96117Y401123D01*
X95772Y400917D01*
X95887Y402260D01*
X96922D01*
G01X95996Y424681D02*
Y427781D01*
X96955D01*
X97261Y427626D01*
X97453Y427419D01*
X97530Y427006D01*
X97453Y426593D01*
X97223Y426334D01*
X96955Y426179D01*
X95996D01*
G01X96955D02*
X97530Y424681D01*
G01X99786D02*
X99863Y425353D01*
X99978Y425921D01*
X100131Y426438D01*
X100323Y427006D01*
X100630Y427781D01*
X99096D01*
G01X76129Y533716D02*
X76321Y533406D01*
X76551Y533199D01*
X76819Y533096D01*
X77126Y533199D01*
X77356Y533406D01*
X77586Y533716D01*
X77663Y534129D01*
Y536196D01*
G01X79268Y535679D02*
X79498Y535989D01*
X79766Y536144D01*
X80073Y536196D01*
X80456Y536093D01*
X80724Y535834D01*
X80801Y535524D01*
X80763Y535214D01*
X80609Y534956D01*
X79843Y534439D01*
X79498Y534078D01*
X79268Y533561D01*
X79191Y533096D01*
X80801D01*
G01X82444Y533458D02*
X82713Y533199D01*
X83019Y533096D01*
X83326Y533199D01*
X83594Y533509D01*
X83786Y533974D01*
X83863Y534439D01*
Y535008D01*
X83786Y535473D01*
X83594Y535886D01*
X83364Y536093D01*
X83096Y536196D01*
X82789Y536093D01*
X82559Y535886D01*
X82406Y535576D01*
X82329Y535163D01*
X82406Y534801D01*
X82598Y534439D01*
X82828Y534233D01*
X83096Y534181D01*
X83403Y534284D01*
X83633Y534543D01*
X83863Y535008D01*
G01X81536Y623201D02*
X76536D01*
Y624785D01*
X76786Y625291D01*
X77119Y625608D01*
X77786Y625735D01*
X78453Y625608D01*
X78869Y625228D01*
X79119Y624785D01*
Y623201D01*
G01Y624785D02*
X81536Y625735D01*
G01X79286Y628618D02*
Y630645D01*
X78703Y630455D01*
X78369Y630138D01*
X78203Y629695D01*
X78286Y629251D01*
X78536Y628871D01*
X79119Y628618D01*
X79619Y628491D01*
X80119D01*
X80619Y628618D01*
X81119Y628935D01*
X81453Y629315D01*
X81536Y629758D01*
X81369Y630201D01*
X80869Y630645D01*
G01X78203Y633528D02*
X81536Y634668D01*
X78203Y635808D01*
G01X81703Y639768D02*
X81619Y639641D01*
X81453D01*
X81369Y639768D01*
X81453Y639895D01*
X81619D01*
X81703Y639768D01*
G01X79453D02*
X79369Y639641D01*
X79203D01*
X79119Y639768D01*
X79203Y639895D01*
X79369D01*
X79453Y639768D01*
G01X81536Y643475D02*
X76536D01*
Y644741D01*
X76786Y645248D01*
X77119Y645628D01*
X77619Y645945D01*
X78203Y646198D01*
X79036Y646261D01*
X79869Y646198D01*
X80453Y645945D01*
X80953Y645628D01*
X81286Y645248D01*
X81536Y644741D01*
Y643475D01*
G01X87277Y718844D02*
Y721944D01*
X88236D01*
X88542Y721789D01*
X88734Y721582D01*
X88811Y721169D01*
X88734Y720756D01*
X88504Y720497D01*
X88236Y720342D01*
X87277D01*
G01X88236D02*
X88811Y718844D01*
G01X90301Y719309D02*
X90531Y719051D01*
X90799Y718896D01*
X91144Y718844D01*
X91489Y718947D01*
X91757Y719154D01*
X91949Y719516D01*
X91987Y719929D01*
X91911Y720342D01*
X91719Y720601D01*
X91451Y720807D01*
X91182Y720859D01*
X90914Y720807D01*
X90569Y720601D01*
X90684Y721944D01*
X91719D01*
G01X93401Y719309D02*
X93631Y719051D01*
X93899Y718896D01*
X94244Y718844D01*
X94589Y718947D01*
X94857Y719154D01*
X95049Y719516D01*
X95087Y719929D01*
X95011Y720342D01*
X94819Y720601D01*
X94551Y720807D01*
X94282Y720859D01*
X94014Y720807D01*
X93669Y720601D01*
X93784Y721944D01*
X94819D01*
G01X87277Y728497D02*
Y731597D01*
X88236D01*
X88542Y731442D01*
X88734Y731235D01*
X88811Y730822D01*
X88734Y730409D01*
X88504Y730150D01*
X88236Y729995D01*
X87277D01*
G01X88236D02*
X88811Y728497D01*
G01X91067D02*
X91144Y729169D01*
X91259Y729737D01*
X91412Y730254D01*
X91604Y730822D01*
X91911Y731597D01*
X90377D01*
G01X94244D02*
X93937Y731494D01*
X93707Y731235D01*
X93554Y730925D01*
X93439Y730512D01*
X93401Y730047D01*
X93439Y729582D01*
X93554Y729169D01*
X93707Y728859D01*
X93937Y728600D01*
X94244Y728497D01*
X94551Y728600D01*
X94781Y728859D01*
X94934Y729169D01*
X95049Y729582D01*
X95087Y730047D01*
X95049Y730512D01*
X94934Y730925D01*
X94781Y731235D01*
X94551Y731494D01*
X94244Y731597D01*
G01X87277Y723556D02*
Y726656D01*
X88236D01*
X88542Y726501D01*
X88734Y726294D01*
X88811Y725881D01*
X88734Y725468D01*
X88504Y725209D01*
X88236Y725054D01*
X87277D01*
G01X88236D02*
X88811Y723556D01*
G01X91067D02*
X91144Y724228D01*
X91259Y724796D01*
X91412Y725313D01*
X91604Y725881D01*
X91911Y726656D01*
X90377D01*
G01X93516Y726139D02*
X93746Y726449D01*
X94014Y726604D01*
X94321Y726656D01*
X94704Y726553D01*
X94972Y726294D01*
X95049Y725984D01*
X95011Y725674D01*
X94857Y725416D01*
X94091Y724899D01*
X93746Y724538D01*
X93516Y724021D01*
X93439Y723556D01*
X95049D01*
G01X87277Y714036D02*
Y717136D01*
X88236D01*
X88542Y716981D01*
X88734Y716774D01*
X88811Y716361D01*
X88734Y715948D01*
X88504Y715689D01*
X88236Y715534D01*
X87277D01*
G01X88236D02*
X88811Y714036D01*
G01X91067D02*
X91144Y714708D01*
X91259Y715276D01*
X91412Y715793D01*
X91604Y716361D01*
X91911Y717136D01*
X90377D01*
G01X93401Y714656D02*
X93631Y714294D01*
X93937Y714088D01*
X94282Y714036D01*
X94589Y714088D01*
X94896Y714346D01*
X95087Y714656D01*
X95126Y714966D01*
X95049Y715328D01*
X94781Y715586D01*
X94512Y715689D01*
X94167D01*
G01X94512D02*
X94742Y715844D01*
X94934Y716103D01*
X95011Y716413D01*
X94934Y716723D01*
X94742Y716981D01*
X94397Y717136D01*
X94052Y717084D01*
X93707Y716878D01*
G01X87246Y742490D02*
Y745590D01*
X88205D01*
X88511Y745435D01*
X88703Y745228D01*
X88780Y744815D01*
X88703Y744402D01*
X88473Y744143D01*
X88205Y743988D01*
X87246D01*
G01X88205D02*
X88780Y742490D01*
G01X90270Y742955D02*
X90500Y742697D01*
X90768Y742542D01*
X91113Y742490D01*
X91458Y742593D01*
X91726Y742800D01*
X91918Y743162D01*
X91956Y743575D01*
X91880Y743988D01*
X91688Y744247D01*
X91420Y744453D01*
X91151Y744505D01*
X90883Y744453D01*
X90538Y744247D01*
X90653Y745590D01*
X91688D01*
G01X94213Y742490D02*
Y745590D01*
X93753Y744970D01*
G01Y742490D02*
X94673D01*
G01X87277Y733347D02*
Y736447D01*
X88236D01*
X88542Y736292D01*
X88734Y736085D01*
X88811Y735672D01*
X88734Y735259D01*
X88504Y735000D01*
X88236Y734845D01*
X87277D01*
G01X88236D02*
X88811Y733347D01*
G01X91604D02*
Y736447D01*
X90186Y734225D01*
X92102D01*
G01X94244Y733347D02*
X94512Y733399D01*
X94819Y733554D01*
X95011Y733812D01*
X95087Y734174D01*
X95011Y734535D01*
X94781Y734845D01*
X94436Y735000D01*
X94052D01*
X93822Y735104D01*
X93631Y735362D01*
X93554Y735724D01*
X93669Y736085D01*
X93937Y736344D01*
X94244Y736447D01*
X94551Y736344D01*
X94819Y736085D01*
X94934Y735724D01*
X94857Y735362D01*
X94666Y735104D01*
X94436Y735000D01*
X94052D01*
X93707Y734845D01*
X93477Y734535D01*
X93401Y734174D01*
X93477Y733812D01*
X93669Y733554D01*
X93976Y733399D01*
X94244Y733347D01*
G01X87277Y738061D02*
Y741161D01*
X88236D01*
X88542Y741006D01*
X88734Y740799D01*
X88811Y740386D01*
X88734Y739973D01*
X88504Y739714D01*
X88236Y739559D01*
X87277D01*
G01X88236D02*
X88811Y738061D01*
G01X91067D02*
X91144Y738733D01*
X91259Y739301D01*
X91412Y739818D01*
X91604Y740386D01*
X91911Y741161D01*
X90377D01*
G01X94244Y738061D02*
Y741161D01*
X93784Y740541D01*
G01Y738061D02*
X94704D01*
G01X86720Y747030D02*
Y750130D01*
X87679D01*
X87985Y749975D01*
X88177Y749768D01*
X88254Y749355D01*
X88177Y748942D01*
X87947Y748683D01*
X87679Y748528D01*
X86720D01*
G01X87679D02*
X88254Y747030D01*
G01X90587D02*
Y750130D01*
X90127Y749510D01*
G01Y747030D02*
X91047D01*
G01X92844Y747650D02*
X93074Y747288D01*
X93380Y747082D01*
X93725Y747030D01*
X94032Y747082D01*
X94339Y747340D01*
X94530Y747650D01*
X94569Y747960D01*
X94492Y748322D01*
X94224Y748580D01*
X93955Y748683D01*
X93610D01*
G01X93955D02*
X94185Y748838D01*
X94377Y749097D01*
X94454Y749407D01*
X94377Y749717D01*
X94185Y749975D01*
X93840Y750130D01*
X93495Y750078D01*
X93150Y749872D01*
G01X96059Y748322D02*
X96327Y748683D01*
X96557Y748890D01*
X96864Y748993D01*
X97132Y748890D01*
X97324Y748683D01*
X97477Y748373D01*
X97515Y748012D01*
X97477Y747702D01*
X97324Y747392D01*
X97094Y747133D01*
X96825Y747030D01*
X96519Y747133D01*
X96250Y747443D01*
X96097Y747908D01*
X96059Y748425D01*
X96135Y749097D01*
X96250Y749458D01*
X96442Y749820D01*
X96710Y750078D01*
X96979Y750130D01*
X97247Y750027D01*
X97439Y749768D01*
G01X93892Y772296D02*
Y775396D01*
X94851D01*
X95157Y775241D01*
X95349Y775034D01*
X95426Y774621D01*
X95349Y774208D01*
X95119Y773949D01*
X94851Y773794D01*
X93892D01*
G01X94851D02*
X95426Y772296D01*
G01X97031Y773588D02*
X97299Y773949D01*
X97529Y774156D01*
X97836Y774259D01*
X98104Y774156D01*
X98296Y773949D01*
X98449Y773639D01*
X98487Y773278D01*
X98449Y772968D01*
X98296Y772658D01*
X98066Y772399D01*
X97797Y772296D01*
X97491Y772399D01*
X97222Y772709D01*
X97069Y773174D01*
X97031Y773691D01*
X97107Y774363D01*
X97222Y774724D01*
X97414Y775086D01*
X97682Y775344D01*
X97951Y775396D01*
X98219Y775293D01*
X98411Y775034D01*
G01X87250Y1070852D02*
Y1073952D01*
X88209D01*
X88515Y1073797D01*
X88707Y1073590D01*
X88784Y1073177D01*
X88707Y1072764D01*
X88477Y1072505D01*
X88209Y1072350D01*
X87250D01*
G01X88209D02*
X88784Y1070852D01*
G01X90274Y1071317D02*
X90504Y1071059D01*
X90772Y1070904D01*
X91117Y1070852D01*
X91462Y1070955D01*
X91730Y1071162D01*
X91922Y1071524D01*
X91960Y1071937D01*
X91884Y1072350D01*
X91692Y1072609D01*
X91424Y1072815D01*
X91155Y1072867D01*
X90887Y1072815D01*
X90542Y1072609D01*
X90657Y1073952D01*
X91692D01*
G01X94140Y1070852D02*
X94217Y1071524D01*
X94332Y1072092D01*
X94485Y1072609D01*
X94677Y1073177D01*
X94984Y1073952D01*
X93450D01*
G01X87250Y1066141D02*
Y1069241D01*
X88209D01*
X88515Y1069086D01*
X88707Y1068879D01*
X88784Y1068466D01*
X88707Y1068053D01*
X88477Y1067794D01*
X88209Y1067639D01*
X87250D01*
G01X88209D02*
X88784Y1066141D01*
G01X91040D02*
X91117Y1066813D01*
X91232Y1067381D01*
X91385Y1067898D01*
X91577Y1068466D01*
X91884Y1069241D01*
X90350D01*
G01X94140Y1066141D02*
X94217Y1066813D01*
X94332Y1067381D01*
X94485Y1067898D01*
X94677Y1068466D01*
X94984Y1069241D01*
X93450D01*
G01X88101Y1095430D02*
Y1098530D01*
X89060D01*
X89366Y1098375D01*
X89558Y1098168D01*
X89635Y1097755D01*
X89558Y1097342D01*
X89328Y1097083D01*
X89060Y1096928D01*
X88101D01*
G01X89060D02*
X89635Y1095430D01*
G01X91125Y1095895D02*
X91355Y1095637D01*
X91623Y1095482D01*
X91968Y1095430D01*
X92313Y1095533D01*
X92581Y1095740D01*
X92773Y1096102D01*
X92811Y1096515D01*
X92735Y1096928D01*
X92543Y1097187D01*
X92275Y1097393D01*
X92006Y1097445D01*
X91738Y1097393D01*
X91393Y1097187D01*
X91508Y1098530D01*
X92543D01*
G01X94340Y1098013D02*
X94570Y1098323D01*
X94838Y1098478D01*
X95145Y1098530D01*
X95528Y1098427D01*
X95796Y1098168D01*
X95873Y1097858D01*
X95835Y1097548D01*
X95681Y1097290D01*
X94915Y1096773D01*
X94570Y1096412D01*
X94340Y1095895D01*
X94263Y1095430D01*
X95873D01*
G01X87161Y1089853D02*
Y1092953D01*
X88120D01*
X88426Y1092798D01*
X88618Y1092591D01*
X88695Y1092178D01*
X88618Y1091765D01*
X88388Y1091506D01*
X88120Y1091351D01*
X87161D01*
G01X88120D02*
X88695Y1089853D01*
G01X90185Y1090318D02*
X90415Y1090060D01*
X90683Y1089905D01*
X91028Y1089853D01*
X91373Y1089956D01*
X91641Y1090163D01*
X91833Y1090525D01*
X91871Y1090938D01*
X91795Y1091351D01*
X91603Y1091610D01*
X91335Y1091816D01*
X91066Y1091868D01*
X90798Y1091816D01*
X90453Y1091610D01*
X90568Y1092953D01*
X91603D01*
G01X93400Y1091145D02*
X93668Y1091506D01*
X93898Y1091713D01*
X94205Y1091816D01*
X94473Y1091713D01*
X94665Y1091506D01*
X94818Y1091196D01*
X94856Y1090835D01*
X94818Y1090525D01*
X94665Y1090215D01*
X94435Y1089956D01*
X94166Y1089853D01*
X93860Y1089956D01*
X93591Y1090266D01*
X93438Y1090731D01*
X93400Y1091248D01*
X93476Y1091920D01*
X93591Y1092281D01*
X93783Y1092643D01*
X94051Y1092901D01*
X94320Y1092953D01*
X94588Y1092850D01*
X94780Y1092591D01*
G01X87250Y1080417D02*
Y1083517D01*
X88209D01*
X88515Y1083362D01*
X88707Y1083155D01*
X88784Y1082742D01*
X88707Y1082329D01*
X88477Y1082070D01*
X88209Y1081915D01*
X87250D01*
G01X88209D02*
X88784Y1080417D01*
G01X91040D02*
X91117Y1081089D01*
X91232Y1081657D01*
X91385Y1082174D01*
X91577Y1082742D01*
X91884Y1083517D01*
X90350D01*
G01X94677Y1080417D02*
Y1083517D01*
X93259Y1081295D01*
X95175D01*
G01X87250Y1075527D02*
Y1078627D01*
X88209D01*
X88515Y1078472D01*
X88707Y1078265D01*
X88784Y1077852D01*
X88707Y1077439D01*
X88477Y1077180D01*
X88209Y1077025D01*
X87250D01*
G01X88209D02*
X88784Y1075527D01*
G01X91040D02*
X91117Y1076199D01*
X91232Y1076767D01*
X91385Y1077284D01*
X91577Y1077852D01*
X91884Y1078627D01*
X90350D01*
G01X93489Y1076819D02*
X93757Y1077180D01*
X93987Y1077387D01*
X94294Y1077490D01*
X94562Y1077387D01*
X94754Y1077180D01*
X94907Y1076870D01*
X94945Y1076509D01*
X94907Y1076199D01*
X94754Y1075889D01*
X94524Y1075630D01*
X94255Y1075527D01*
X93949Y1075630D01*
X93680Y1075940D01*
X93527Y1076405D01*
X93489Y1076922D01*
X93565Y1077594D01*
X93680Y1077955D01*
X93872Y1078317D01*
X94140Y1078575D01*
X94409Y1078627D01*
X94677Y1078524D01*
X94869Y1078265D01*
G01X87250Y1085721D02*
Y1088821D01*
X88209D01*
X88515Y1088666D01*
X88707Y1088459D01*
X88784Y1088046D01*
X88707Y1087633D01*
X88477Y1087374D01*
X88209Y1087219D01*
X87250D01*
G01X88209D02*
X88784Y1085721D01*
G01X91040D02*
X91117Y1086393D01*
X91232Y1086961D01*
X91385Y1087478D01*
X91577Y1088046D01*
X91884Y1088821D01*
X90350D01*
G01X93374Y1086186D02*
X93604Y1085928D01*
X93872Y1085773D01*
X94217Y1085721D01*
X94562Y1085824D01*
X94830Y1086031D01*
X95022Y1086393D01*
X95060Y1086806D01*
X94984Y1087219D01*
X94792Y1087478D01*
X94524Y1087684D01*
X94255Y1087736D01*
X93987Y1087684D01*
X93642Y1087478D01*
X93757Y1088821D01*
X94792D01*
G01X92675Y1100448D02*
Y1103548D01*
X93634D01*
X93940Y1103393D01*
X94132Y1103186D01*
X94209Y1102773D01*
X94132Y1102360D01*
X93902Y1102101D01*
X93634Y1101946D01*
X92675D01*
G01X93634D02*
X94209Y1100448D01*
G01X96542D02*
Y1103548D01*
X96082Y1102928D01*
G01Y1100448D02*
X97002D01*
G01X98799Y1101068D02*
X99029Y1100706D01*
X99335Y1100500D01*
X99680Y1100448D01*
X99987Y1100500D01*
X100294Y1100758D01*
X100485Y1101068D01*
X100524Y1101378D01*
X100447Y1101740D01*
X100179Y1101998D01*
X99910Y1102101D01*
X99565D01*
G01X99910D02*
X100140Y1102256D01*
X100332Y1102515D01*
X100409Y1102825D01*
X100332Y1103135D01*
X100140Y1103393D01*
X99795Y1103548D01*
X99450Y1103496D01*
X99105Y1103290D01*
G01X102665Y1100448D02*
X102742Y1101120D01*
X102857Y1101688D01*
X103010Y1102205D01*
X103202Y1102773D01*
X103509Y1103548D01*
X101975D01*
G01X94184Y1120735D02*
Y1123835D01*
X95143D01*
X95449Y1123680D01*
X95641Y1123473D01*
X95718Y1123060D01*
X95641Y1122647D01*
X95411Y1122388D01*
X95143Y1122233D01*
X94184D01*
G01X95143D02*
X95718Y1120735D01*
G01X97323Y1123318D02*
X97553Y1123628D01*
X97821Y1123783D01*
X98128Y1123835D01*
X98511Y1123732D01*
X98779Y1123473D01*
X98856Y1123163D01*
X98818Y1122853D01*
X98664Y1122595D01*
X97898Y1122078D01*
X97553Y1121717D01*
X97323Y1121200D01*
X97246Y1120735D01*
X98856D01*
G01X101151Y1123835D02*
X100844Y1123732D01*
X100614Y1123473D01*
X100461Y1123163D01*
X100346Y1122750D01*
X100308Y1122285D01*
X100346Y1121820D01*
X100461Y1121407D01*
X100614Y1121097D01*
X100844Y1120838D01*
X101151Y1120735D01*
X101458Y1120838D01*
X101688Y1121097D01*
X101841Y1121407D01*
X101956Y1121820D01*
X101994Y1122285D01*
X101956Y1122750D01*
X101841Y1123163D01*
X101688Y1123473D01*
X101458Y1123732D01*
X101151Y1123835D01*
G01X76804Y1322586D02*
X79026D01*
X79491Y1322739D01*
X79801Y1323046D01*
X79904Y1323429D01*
X79801Y1323812D01*
X79491Y1324119D01*
X79026Y1324272D01*
X76804D01*
G01X79904Y1326529D02*
X76804D01*
X77424Y1326069D01*
G01X79904D02*
Y1326989D01*
G01X86762Y1418984D02*
Y1422084D01*
X87721D01*
X88027Y1421929D01*
X88219Y1421722D01*
X88296Y1421309D01*
X88219Y1420896D01*
X87989Y1420637D01*
X87721Y1420482D01*
X86762D01*
G01X87721D02*
X88296Y1418984D01*
G01X89786Y1419449D02*
X90016Y1419191D01*
X90284Y1419036D01*
X90629Y1418984D01*
X90974Y1419087D01*
X91242Y1419294D01*
X91434Y1419656D01*
X91472Y1420069D01*
X91396Y1420482D01*
X91204Y1420741D01*
X90936Y1420947D01*
X90667Y1420999D01*
X90399Y1420947D01*
X90054Y1420741D01*
X90169Y1422084D01*
X91204D01*
G01X93077Y1419346D02*
X93346Y1419087D01*
X93652Y1418984D01*
X93959Y1419087D01*
X94227Y1419397D01*
X94419Y1419862D01*
X94496Y1420327D01*
Y1420896D01*
X94419Y1421361D01*
X94227Y1421774D01*
X93997Y1421981D01*
X93729Y1422084D01*
X93422Y1421981D01*
X93192Y1421774D01*
X93039Y1421464D01*
X92962Y1421051D01*
X93039Y1420689D01*
X93231Y1420327D01*
X93461Y1420121D01*
X93729Y1420069D01*
X94036Y1420172D01*
X94266Y1420431D01*
X94496Y1420896D01*
G01X86762Y1433533D02*
Y1436633D01*
X87721D01*
X88027Y1436478D01*
X88219Y1436271D01*
X88296Y1435858D01*
X88219Y1435445D01*
X87989Y1435186D01*
X87721Y1435031D01*
X86762D01*
G01X87721D02*
X88296Y1433533D01*
G01X90552D02*
X90629Y1434205D01*
X90744Y1434773D01*
X90897Y1435290D01*
X91089Y1435858D01*
X91396Y1436633D01*
X89862D01*
G01X93729Y1433533D02*
X93997Y1433585D01*
X94304Y1433740D01*
X94496Y1433998D01*
X94572Y1434360D01*
X94496Y1434721D01*
X94266Y1435031D01*
X93921Y1435186D01*
X93537D01*
X93307Y1435290D01*
X93116Y1435548D01*
X93039Y1435910D01*
X93154Y1436271D01*
X93422Y1436530D01*
X93729Y1436633D01*
X94036Y1436530D01*
X94304Y1436271D01*
X94419Y1435910D01*
X94342Y1435548D01*
X94151Y1435290D01*
X93921Y1435186D01*
X93537D01*
X93192Y1435031D01*
X92962Y1434721D01*
X92886Y1434360D01*
X92962Y1433998D01*
X93154Y1433740D01*
X93461Y1433585D01*
X93729Y1433533D01*
G01X86762Y1428687D02*
Y1431787D01*
X87721D01*
X88027Y1431632D01*
X88219Y1431425D01*
X88296Y1431012D01*
X88219Y1430599D01*
X87989Y1430340D01*
X87721Y1430185D01*
X86762D01*
G01X87721D02*
X88296Y1428687D01*
G01X90629D02*
X90897Y1428739D01*
X91204Y1428894D01*
X91396Y1429152D01*
X91472Y1429514D01*
X91396Y1429875D01*
X91166Y1430185D01*
X90821Y1430340D01*
X90437D01*
X90207Y1430444D01*
X90016Y1430702D01*
X89939Y1431064D01*
X90054Y1431425D01*
X90322Y1431684D01*
X90629Y1431787D01*
X90936Y1431684D01*
X91204Y1431425D01*
X91319Y1431064D01*
X91242Y1430702D01*
X91051Y1430444D01*
X90821Y1430340D01*
X90437D01*
X90092Y1430185D01*
X89862Y1429875D01*
X89786Y1429514D01*
X89862Y1429152D01*
X90054Y1428894D01*
X90361Y1428739D01*
X90629Y1428687D01*
G01X93729Y1431787D02*
X93422Y1431684D01*
X93192Y1431425D01*
X93039Y1431115D01*
X92924Y1430702D01*
X92886Y1430237D01*
X92924Y1429772D01*
X93039Y1429359D01*
X93192Y1429049D01*
X93422Y1428790D01*
X93729Y1428687D01*
X94036Y1428790D01*
X94266Y1429049D01*
X94419Y1429359D01*
X94534Y1429772D01*
X94572Y1430237D01*
X94534Y1430702D01*
X94419Y1431115D01*
X94266Y1431425D01*
X94036Y1431684D01*
X93729Y1431787D01*
G01X86762Y1423832D02*
Y1426932D01*
X87721D01*
X88027Y1426777D01*
X88219Y1426570D01*
X88296Y1426157D01*
X88219Y1425744D01*
X87989Y1425485D01*
X87721Y1425330D01*
X86762D01*
G01X87721D02*
X88296Y1423832D01*
G01X90629D02*
X90897Y1423884D01*
X91204Y1424039D01*
X91396Y1424297D01*
X91472Y1424659D01*
X91396Y1425020D01*
X91166Y1425330D01*
X90821Y1425485D01*
X90437D01*
X90207Y1425589D01*
X90016Y1425847D01*
X89939Y1426209D01*
X90054Y1426570D01*
X90322Y1426829D01*
X90629Y1426932D01*
X90936Y1426829D01*
X91204Y1426570D01*
X91319Y1426209D01*
X91242Y1425847D01*
X91051Y1425589D01*
X90821Y1425485D01*
X90437D01*
X90092Y1425330D01*
X89862Y1425020D01*
X89786Y1424659D01*
X89862Y1424297D01*
X90054Y1424039D01*
X90361Y1423884D01*
X90629Y1423832D01*
G01X93729D02*
Y1426932D01*
X93269Y1426312D01*
G01Y1423832D02*
X94189D01*
G01X87069Y1448040D02*
Y1451140D01*
X88028D01*
X88334Y1450985D01*
X88526Y1450778D01*
X88603Y1450365D01*
X88526Y1449952D01*
X88296Y1449693D01*
X88028Y1449538D01*
X87069D01*
G01X88028D02*
X88603Y1448040D01*
G01X90093Y1448505D02*
X90323Y1448247D01*
X90591Y1448092D01*
X90936Y1448040D01*
X91281Y1448143D01*
X91549Y1448350D01*
X91741Y1448712D01*
X91779Y1449125D01*
X91703Y1449538D01*
X91511Y1449797D01*
X91243Y1450003D01*
X90974Y1450055D01*
X90706Y1450003D01*
X90361Y1449797D01*
X90476Y1451140D01*
X91511D01*
G01X93193Y1448660D02*
X93423Y1448298D01*
X93729Y1448092D01*
X94074Y1448040D01*
X94381Y1448092D01*
X94688Y1448350D01*
X94879Y1448660D01*
X94918Y1448970D01*
X94841Y1449332D01*
X94573Y1449590D01*
X94304Y1449693D01*
X93959D01*
G01X94304D02*
X94534Y1449848D01*
X94726Y1450107D01*
X94803Y1450417D01*
X94726Y1450727D01*
X94534Y1450985D01*
X94189Y1451140D01*
X93844Y1451088D01*
X93499Y1450882D01*
G01X86762Y1443235D02*
Y1446335D01*
X87721D01*
X88027Y1446180D01*
X88219Y1445973D01*
X88296Y1445560D01*
X88219Y1445147D01*
X87989Y1444888D01*
X87721Y1444733D01*
X86762D01*
G01X87721D02*
X88296Y1443235D01*
G01X89786Y1443700D02*
X90016Y1443442D01*
X90284Y1443287D01*
X90629Y1443235D01*
X90974Y1443338D01*
X91242Y1443545D01*
X91434Y1443907D01*
X91472Y1444320D01*
X91396Y1444733D01*
X91204Y1444992D01*
X90936Y1445198D01*
X90667Y1445250D01*
X90399Y1445198D01*
X90054Y1444992D01*
X90169Y1446335D01*
X91204D01*
G01X93729Y1443235D02*
X93997Y1443287D01*
X94304Y1443442D01*
X94496Y1443700D01*
X94572Y1444062D01*
X94496Y1444423D01*
X94266Y1444733D01*
X93921Y1444888D01*
X93537D01*
X93307Y1444992D01*
X93116Y1445250D01*
X93039Y1445612D01*
X93154Y1445973D01*
X93422Y1446232D01*
X93729Y1446335D01*
X94036Y1446232D01*
X94304Y1445973D01*
X94419Y1445612D01*
X94342Y1445250D01*
X94151Y1444992D01*
X93921Y1444888D01*
X93537D01*
X93192Y1444733D01*
X92962Y1444423D01*
X92886Y1444062D01*
X92962Y1443700D01*
X93154Y1443442D01*
X93461Y1443287D01*
X93729Y1443235D01*
G01X86762Y1438472D02*
Y1441572D01*
X87721D01*
X88027Y1441417D01*
X88219Y1441210D01*
X88296Y1440797D01*
X88219Y1440384D01*
X87989Y1440125D01*
X87721Y1439970D01*
X86762D01*
G01X87721D02*
X88296Y1438472D01*
G01X90552D02*
X90629Y1439144D01*
X90744Y1439712D01*
X90897Y1440229D01*
X91089Y1440797D01*
X91396Y1441572D01*
X89862D01*
G01X93077Y1438834D02*
X93346Y1438575D01*
X93652Y1438472D01*
X93959Y1438575D01*
X94227Y1438885D01*
X94419Y1439350D01*
X94496Y1439815D01*
Y1440384D01*
X94419Y1440849D01*
X94227Y1441262D01*
X93997Y1441469D01*
X93729Y1441572D01*
X93422Y1441469D01*
X93192Y1441262D01*
X93039Y1440952D01*
X92962Y1440539D01*
X93039Y1440177D01*
X93231Y1439815D01*
X93461Y1439609D01*
X93729Y1439557D01*
X94036Y1439660D01*
X94266Y1439919D01*
X94496Y1440384D01*
G01X86674Y1454224D02*
Y1457324D01*
X87633D01*
X87939Y1457169D01*
X88131Y1456962D01*
X88208Y1456549D01*
X88131Y1456136D01*
X87901Y1455877D01*
X87633Y1455722D01*
X86674D01*
G01X87633D02*
X88208Y1454224D01*
G01X90541D02*
Y1457324D01*
X90081Y1456704D01*
G01Y1454224D02*
X91001D01*
G01X92798Y1454844D02*
X93028Y1454482D01*
X93334Y1454276D01*
X93679Y1454224D01*
X93986Y1454276D01*
X94293Y1454534D01*
X94484Y1454844D01*
X94523Y1455154D01*
X94446Y1455516D01*
X94178Y1455774D01*
X93909Y1455877D01*
X93564D01*
G01X93909D02*
X94139Y1456032D01*
X94331Y1456291D01*
X94408Y1456601D01*
X94331Y1456911D01*
X94139Y1457169D01*
X93794Y1457324D01*
X93449Y1457272D01*
X93104Y1457066D01*
G01X96741Y1454224D02*
X97009Y1454276D01*
X97316Y1454431D01*
X97508Y1454689D01*
X97584Y1455051D01*
X97508Y1455412D01*
X97278Y1455722D01*
X96933Y1455877D01*
X96549D01*
X96319Y1455981D01*
X96128Y1456239D01*
X96051Y1456601D01*
X96166Y1456962D01*
X96434Y1457221D01*
X96741Y1457324D01*
X97048Y1457221D01*
X97316Y1456962D01*
X97431Y1456601D01*
X97354Y1456239D01*
X97163Y1455981D01*
X96933Y1455877D01*
X96549D01*
X96204Y1455722D01*
X95974Y1455412D01*
X95898Y1455051D01*
X95974Y1454689D01*
X96166Y1454431D01*
X96473Y1454276D01*
X96741Y1454224D01*
G01X94762Y1468226D02*
Y1471326D01*
X95721D01*
X96027Y1471171D01*
X96219Y1470964D01*
X96296Y1470551D01*
X96219Y1470138D01*
X95989Y1469879D01*
X95721Y1469724D01*
X94762D01*
G01X95721D02*
X96296Y1468226D01*
G01X98629D02*
Y1471326D01*
X98169Y1470706D01*
G01Y1468226D02*
X99089D01*
G01X101077Y1468588D02*
X101346Y1468329D01*
X101652Y1468226D01*
X101959Y1468329D01*
X102227Y1468639D01*
X102419Y1469104D01*
X102496Y1469569D01*
Y1470138D01*
X102419Y1470603D01*
X102227Y1471016D01*
X101997Y1471223D01*
X101729Y1471326D01*
X101422Y1471223D01*
X101192Y1471016D01*
X101039Y1470706D01*
X100962Y1470293D01*
X101039Y1469931D01*
X101231Y1469569D01*
X101461Y1469363D01*
X101729Y1469311D01*
X102036Y1469414D01*
X102266Y1469673D01*
X102496Y1470138D01*
G01X89472Y1759911D02*
Y1763011D01*
X90431D01*
X90737Y1762856D01*
X90929Y1762649D01*
X91006Y1762236D01*
X90929Y1761823D01*
X90699Y1761564D01*
X90431Y1761409D01*
X89472D01*
G01X90431D02*
X91006Y1759911D01*
G01X92611Y1761203D02*
X92879Y1761564D01*
X93109Y1761771D01*
X93416Y1761874D01*
X93684Y1761771D01*
X93876Y1761564D01*
X94029Y1761254D01*
X94067Y1760893D01*
X94029Y1760583D01*
X93876Y1760273D01*
X93646Y1760014D01*
X93377Y1759911D01*
X93071Y1760014D01*
X92802Y1760324D01*
X92649Y1760789D01*
X92611Y1761306D01*
X92687Y1761978D01*
X92802Y1762339D01*
X92994Y1762701D01*
X93262Y1762959D01*
X93531Y1763011D01*
X93799Y1762908D01*
X93991Y1762649D01*
G01X96439Y1759911D02*
Y1763011D01*
X95979Y1762391D01*
G01Y1759911D02*
X96899D01*
G01X89472Y1769611D02*
Y1772711D01*
X90431D01*
X90737Y1772556D01*
X90929Y1772349D01*
X91006Y1771936D01*
X90929Y1771523D01*
X90699Y1771264D01*
X90431Y1771109D01*
X89472D01*
G01X90431D02*
X91006Y1769611D01*
G01X93339D02*
X93607Y1769663D01*
X93914Y1769818D01*
X94106Y1770076D01*
X94182Y1770438D01*
X94106Y1770799D01*
X93876Y1771109D01*
X93531Y1771264D01*
X93147D01*
X92917Y1771368D01*
X92726Y1771626D01*
X92649Y1771988D01*
X92764Y1772349D01*
X93032Y1772608D01*
X93339Y1772711D01*
X93646Y1772608D01*
X93914Y1772349D01*
X94029Y1771988D01*
X93952Y1771626D01*
X93761Y1771368D01*
X93531Y1771264D01*
X93147D01*
X92802Y1771109D01*
X92572Y1770799D01*
X92496Y1770438D01*
X92572Y1770076D01*
X92764Y1769818D01*
X93071Y1769663D01*
X93339Y1769611D01*
G01X96899D02*
Y1772711D01*
X95481Y1770489D01*
X97397D01*
G01X89472Y1764806D02*
Y1767906D01*
X90431D01*
X90737Y1767751D01*
X90929Y1767544D01*
X91006Y1767131D01*
X90929Y1766718D01*
X90699Y1766459D01*
X90431Y1766304D01*
X89472D01*
G01X90431D02*
X91006Y1764806D01*
G01X93339D02*
X93607Y1764858D01*
X93914Y1765013D01*
X94106Y1765271D01*
X94182Y1765633D01*
X94106Y1765994D01*
X93876Y1766304D01*
X93531Y1766459D01*
X93147D01*
X92917Y1766563D01*
X92726Y1766821D01*
X92649Y1767183D01*
X92764Y1767544D01*
X93032Y1767803D01*
X93339Y1767906D01*
X93646Y1767803D01*
X93914Y1767544D01*
X94029Y1767183D01*
X93952Y1766821D01*
X93761Y1766563D01*
X93531Y1766459D01*
X93147D01*
X92802Y1766304D01*
X92572Y1765994D01*
X92496Y1765633D01*
X92572Y1765271D01*
X92764Y1765013D01*
X93071Y1764858D01*
X93339Y1764806D01*
G01X95596Y1765271D02*
X95826Y1765013D01*
X96094Y1764858D01*
X96439Y1764806D01*
X96784Y1764909D01*
X97052Y1765116D01*
X97244Y1765478D01*
X97282Y1765891D01*
X97206Y1766304D01*
X97014Y1766563D01*
X96746Y1766769D01*
X96477Y1766821D01*
X96209Y1766769D01*
X95864Y1766563D01*
X95979Y1767906D01*
X97014D01*
G01X89154Y1789204D02*
Y1792304D01*
X90113D01*
X90419Y1792149D01*
X90611Y1791942D01*
X90688Y1791529D01*
X90611Y1791116D01*
X90381Y1790857D01*
X90113Y1790702D01*
X89154D01*
G01X90113D02*
X90688Y1789204D01*
G01X92178Y1789669D02*
X92408Y1789411D01*
X92676Y1789256D01*
X93021Y1789204D01*
X93366Y1789307D01*
X93634Y1789514D01*
X93826Y1789876D01*
X93864Y1790289D01*
X93788Y1790702D01*
X93596Y1790961D01*
X93328Y1791167D01*
X93059Y1791219D01*
X92791Y1791167D01*
X92446Y1790961D01*
X92561Y1792304D01*
X93596D01*
G01X96581Y1789204D02*
Y1792304D01*
X95163Y1790082D01*
X97079D01*
G01X89472Y1784655D02*
Y1787755D01*
X90431D01*
X90737Y1787600D01*
X90929Y1787393D01*
X91006Y1786980D01*
X90929Y1786567D01*
X90699Y1786308D01*
X90431Y1786153D01*
X89472D01*
G01X90431D02*
X91006Y1784655D01*
G01X92611Y1785947D02*
X92879Y1786308D01*
X93109Y1786515D01*
X93416Y1786618D01*
X93684Y1786515D01*
X93876Y1786308D01*
X94029Y1785998D01*
X94067Y1785637D01*
X94029Y1785327D01*
X93876Y1785017D01*
X93646Y1784758D01*
X93377Y1784655D01*
X93071Y1784758D01*
X92802Y1785068D01*
X92649Y1785533D01*
X92611Y1786050D01*
X92687Y1786722D01*
X92802Y1787083D01*
X92994Y1787445D01*
X93262Y1787703D01*
X93531Y1787755D01*
X93799Y1787652D01*
X93991Y1787393D01*
G01X96439Y1787755D02*
X96132Y1787652D01*
X95902Y1787393D01*
X95749Y1787083D01*
X95634Y1786670D01*
X95596Y1786205D01*
X95634Y1785740D01*
X95749Y1785327D01*
X95902Y1785017D01*
X96132Y1784758D01*
X96439Y1784655D01*
X96746Y1784758D01*
X96976Y1785017D01*
X97129Y1785327D01*
X97244Y1785740D01*
X97282Y1786205D01*
X97244Y1786670D01*
X97129Y1787083D01*
X96976Y1787393D01*
X96746Y1787652D01*
X96439Y1787755D01*
G01X89472Y1774598D02*
Y1777698D01*
X90431D01*
X90737Y1777543D01*
X90929Y1777336D01*
X91006Y1776923D01*
X90929Y1776510D01*
X90699Y1776251D01*
X90431Y1776096D01*
X89472D01*
G01X90431D02*
X91006Y1774598D01*
G01X93339D02*
X93607Y1774650D01*
X93914Y1774805D01*
X94106Y1775063D01*
X94182Y1775425D01*
X94106Y1775786D01*
X93876Y1776096D01*
X93531Y1776251D01*
X93147D01*
X92917Y1776355D01*
X92726Y1776613D01*
X92649Y1776975D01*
X92764Y1777336D01*
X93032Y1777595D01*
X93339Y1777698D01*
X93646Y1777595D01*
X93914Y1777336D01*
X94029Y1776975D01*
X93952Y1776613D01*
X93761Y1776355D01*
X93531Y1776251D01*
X93147D01*
X92802Y1776096D01*
X92572Y1775786D01*
X92496Y1775425D01*
X92572Y1775063D01*
X92764Y1774805D01*
X93071Y1774650D01*
X93339Y1774598D01*
G01X95711Y1777181D02*
X95941Y1777491D01*
X96209Y1777646D01*
X96516Y1777698D01*
X96899Y1777595D01*
X97167Y1777336D01*
X97244Y1777026D01*
X97206Y1776716D01*
X97052Y1776458D01*
X96286Y1775941D01*
X95941Y1775580D01*
X95711Y1775063D01*
X95634Y1774598D01*
X97244D01*
G01X89472Y1779626D02*
Y1782726D01*
X90431D01*
X90737Y1782571D01*
X90929Y1782364D01*
X91006Y1781951D01*
X90929Y1781538D01*
X90699Y1781279D01*
X90431Y1781124D01*
X89472D01*
G01X90431D02*
X91006Y1779626D01*
G01X93339D02*
X93607Y1779678D01*
X93914Y1779833D01*
X94106Y1780091D01*
X94182Y1780453D01*
X94106Y1780814D01*
X93876Y1781124D01*
X93531Y1781279D01*
X93147D01*
X92917Y1781383D01*
X92726Y1781641D01*
X92649Y1782003D01*
X92764Y1782364D01*
X93032Y1782623D01*
X93339Y1782726D01*
X93646Y1782623D01*
X93914Y1782364D01*
X94029Y1782003D01*
X93952Y1781641D01*
X93761Y1781383D01*
X93531Y1781279D01*
X93147D01*
X92802Y1781124D01*
X92572Y1780814D01*
X92496Y1780453D01*
X92572Y1780091D01*
X92764Y1779833D01*
X93071Y1779678D01*
X93339Y1779626D01*
G01X95596Y1780246D02*
X95826Y1779884D01*
X96132Y1779678D01*
X96477Y1779626D01*
X96784Y1779678D01*
X97091Y1779936D01*
X97282Y1780246D01*
X97321Y1780556D01*
X97244Y1780918D01*
X96976Y1781176D01*
X96707Y1781279D01*
X96362D01*
G01X96707D02*
X96937Y1781434D01*
X97129Y1781693D01*
X97206Y1782003D01*
X97129Y1782313D01*
X96937Y1782571D01*
X96592Y1782726D01*
X96247Y1782674D01*
X95902Y1782468D01*
G01X94423Y1817202D02*
Y1820302D01*
X95382D01*
X95688Y1820147D01*
X95880Y1819940D01*
X95957Y1819527D01*
X95880Y1819114D01*
X95650Y1818855D01*
X95382Y1818700D01*
X94423D01*
G01X95382D02*
X95957Y1817202D01*
G01X97562Y1819785D02*
X97792Y1820095D01*
X98060Y1820250D01*
X98367Y1820302D01*
X98750Y1820199D01*
X99018Y1819940D01*
X99095Y1819630D01*
X99057Y1819320D01*
X98903Y1819062D01*
X98137Y1818545D01*
X97792Y1818184D01*
X97562Y1817667D01*
X97485Y1817202D01*
X99095D01*
G01X100662Y1819785D02*
X100892Y1820095D01*
X101160Y1820250D01*
X101467Y1820302D01*
X101850Y1820199D01*
X102118Y1819940D01*
X102195Y1819630D01*
X102157Y1819320D01*
X102003Y1819062D01*
X101237Y1818545D01*
X100892Y1818184D01*
X100662Y1817667D01*
X100585Y1817202D01*
X102195D01*
G01X90338Y1796309D02*
Y1799409D01*
X91297D01*
X91603Y1799254D01*
X91795Y1799047D01*
X91872Y1798634D01*
X91795Y1798221D01*
X91565Y1797962D01*
X91297Y1797807D01*
X90338D01*
G01X91297D02*
X91872Y1796309D01*
G01X94205D02*
Y1799409D01*
X93745Y1798789D01*
G01Y1796309D02*
X94665D01*
G01X96462Y1796929D02*
X96692Y1796567D01*
X96998Y1796361D01*
X97343Y1796309D01*
X97650Y1796361D01*
X97957Y1796619D01*
X98148Y1796929D01*
X98187Y1797239D01*
X98110Y1797601D01*
X97842Y1797859D01*
X97573Y1797962D01*
X97228D01*
G01X97573D02*
X97803Y1798117D01*
X97995Y1798376D01*
X98072Y1798686D01*
X97995Y1798996D01*
X97803Y1799254D01*
X97458Y1799409D01*
X97113Y1799357D01*
X96768Y1799151D01*
G01X99753Y1796671D02*
X100022Y1796412D01*
X100328Y1796309D01*
X100635Y1796412D01*
X100903Y1796722D01*
X101095Y1797187D01*
X101172Y1797652D01*
Y1798221D01*
X101095Y1798686D01*
X100903Y1799099D01*
X100673Y1799306D01*
X100405Y1799409D01*
X100098Y1799306D01*
X99868Y1799099D01*
X99715Y1798789D01*
X99638Y1798376D01*
X99715Y1798014D01*
X99907Y1797652D01*
X100137Y1797446D01*
X100405Y1797394D01*
X100712Y1797497D01*
X100942Y1797756D01*
X101172Y1798221D01*
G01X148326Y346024D02*
X111514D01*
Y118D01*
X148326D01*
Y346024D01*
G01X101204Y8567D02*
Y11667D01*
X102163D01*
X102469Y11512D01*
X102661Y11305D01*
X102738Y10892D01*
X102661Y10479D01*
X102431Y10220D01*
X102163Y10065D01*
X101204D01*
G01X102163D02*
X102738Y8567D01*
G01X105531D02*
Y11667D01*
X104113Y9445D01*
X106029D01*
G01X107328Y9032D02*
X107558Y8774D01*
X107826Y8619D01*
X108171Y8567D01*
X108516Y8670D01*
X108784Y8877D01*
X108976Y9239D01*
X109014Y9652D01*
X108938Y10065D01*
X108746Y10324D01*
X108478Y10530D01*
X108209Y10582D01*
X107941Y10530D01*
X107596Y10324D01*
X107711Y11667D01*
X108746D01*
G01X101204Y4334D02*
Y7434D01*
X102163D01*
X102469Y7279D01*
X102661Y7072D01*
X102738Y6659D01*
X102661Y6246D01*
X102431Y5987D01*
X102163Y5832D01*
X101204D01*
G01X102163D02*
X102738Y4334D01*
G01X104343Y5626D02*
X104611Y5987D01*
X104841Y6194D01*
X105148Y6297D01*
X105416Y6194D01*
X105608Y5987D01*
X105761Y5677D01*
X105799Y5316D01*
X105761Y5006D01*
X105608Y4696D01*
X105378Y4437D01*
X105109Y4334D01*
X104803Y4437D01*
X104534Y4747D01*
X104381Y5212D01*
X104343Y5729D01*
X104419Y6401D01*
X104534Y6762D01*
X104726Y7124D01*
X104994Y7382D01*
X105263Y7434D01*
X105531Y7331D01*
X105723Y7072D01*
G01X107328Y4799D02*
X107558Y4541D01*
X107826Y4386D01*
X108171Y4334D01*
X108516Y4437D01*
X108784Y4644D01*
X108976Y5006D01*
X109014Y5419D01*
X108938Y5832D01*
X108746Y6091D01*
X108478Y6297D01*
X108209Y6349D01*
X107941Y6297D01*
X107596Y6091D01*
X107711Y7434D01*
X108746D01*
G01X118621Y53288D02*
Y1122D01*
G01D02*
X418149D01*
G01X112464Y12371D02*
X112694Y12009D01*
X113000Y11803D01*
X113345Y11751D01*
X113652Y11803D01*
X113959Y12061D01*
X114150Y12371D01*
X114189Y12681D01*
X114112Y13043D01*
X113844Y13301D01*
X113575Y13404D01*
X113230D01*
G01X113575D02*
X113805Y13559D01*
X113997Y13818D01*
X114074Y14128D01*
X113997Y14438D01*
X113805Y14696D01*
X113460Y14851D01*
X113115Y14799D01*
X112770Y14593D01*
G01X115679Y14334D02*
X115909Y14644D01*
X116177Y14799D01*
X116484Y14851D01*
X116867Y14748D01*
X117135Y14489D01*
X117212Y14179D01*
X117174Y13869D01*
X117020Y13611D01*
X116254Y13094D01*
X115909Y12733D01*
X115679Y12216D01*
X115602Y11751D01*
X117212D01*
G01X99253Y34453D02*
X105453D01*
Y31253D01*
X99253D01*
Y34453D01*
G01X104320Y21680D02*
X110520D01*
Y18480D01*
X104320D01*
Y21680D01*
G01X99253Y29920D02*
X105453D01*
Y26720D01*
X99253D01*
Y29920D01*
G01X99168Y25803D02*
X105368D01*
Y22603D01*
X99168D01*
Y25803D01*
G01X104320Y17447D02*
X110520D01*
Y14247D01*
X104320D01*
Y17447D01*
G01X109615Y44685D02*
X103415D01*
Y47885D01*
X109615D01*
Y44685D01*
G01X103407Y43403D02*
X109607D01*
Y40203D01*
X103407D01*
Y43403D01*
G01X99253Y39038D02*
X105453D01*
Y35838D01*
X99253D01*
Y39038D01*
G01X418149Y53288D02*
X118621D01*
G01X102612Y79786D02*
X108812D01*
Y76586D01*
X102612D01*
Y79786D01*
G01X108868Y82880D02*
Y76680D01*
X105668D01*
Y82880D01*
X108868D01*
G01X104986Y64830D02*
X101886D01*
Y65789D01*
X102041Y66095D01*
X102248Y66287D01*
X102661Y66364D01*
X103074Y66287D01*
X103333Y66057D01*
X103488Y65789D01*
Y64830D01*
G01Y65789D02*
X104986Y66364D01*
G01Y68697D02*
X101886D01*
X102506Y68237D01*
G01X104986D02*
Y69157D01*
G01Y71797D02*
X101886D01*
X102506Y71337D01*
G01X104986D02*
Y72257D01*
G01X104366Y74054D02*
X104728Y74284D01*
X104934Y74590D01*
X104986Y74935D01*
X104934Y75242D01*
X104676Y75549D01*
X104366Y75740D01*
X104056Y75779D01*
X103694Y75702D01*
X103436Y75434D01*
X103333Y75165D01*
Y74820D01*
G01Y75165D02*
X103178Y75395D01*
X102919Y75587D01*
X102609Y75664D01*
X102299Y75587D01*
X102041Y75395D01*
X101886Y75050D01*
X101938Y74705D01*
X102144Y74360D01*
G01X105663Y73530D02*
Y79730D01*
X108863D01*
Y73530D01*
X105663D01*
G01X101202Y59850D02*
X107402D01*
Y56650D01*
X101202D01*
Y59850D01*
G01X104823Y84689D02*
X101723D01*
Y85648D01*
X101878Y85954D01*
X102085Y86146D01*
X102498Y86223D01*
X102911Y86146D01*
X103170Y85916D01*
X103325Y85648D01*
Y84689D01*
G01Y85648D02*
X104823Y86223D01*
G01Y88556D02*
X104771Y88824D01*
X104616Y89131D01*
X104358Y89323D01*
X103996Y89399D01*
X103635Y89323D01*
X103325Y89093D01*
X103170Y88748D01*
Y88364D01*
X103066Y88134D01*
X102808Y87943D01*
X102446Y87866D01*
X102085Y87981D01*
X101826Y88249D01*
X101723Y88556D01*
X101826Y88863D01*
X102085Y89131D01*
X102446Y89246D01*
X102808Y89169D01*
X103066Y88978D01*
X103170Y88748D01*
Y88364D01*
X103325Y88019D01*
X103635Y87789D01*
X103996Y87713D01*
X104358Y87789D01*
X104616Y87981D01*
X104771Y88288D01*
X104823Y88556D01*
G01Y91579D02*
X104151Y91656D01*
X103583Y91771D01*
X103066Y91924D01*
X102498Y92116D01*
X101723Y92423D01*
Y90889D01*
G01X118621Y228288D02*
Y176122D01*
G01D02*
X418149D01*
G01Y228288D02*
X118621D01*
G01X109195Y329268D02*
Y332368D01*
X108735Y331748D01*
G01Y329268D02*
X109655D01*
G01X105759Y367064D02*
X105989Y366702D01*
X106295Y366496D01*
X106640Y366444D01*
X106947Y366496D01*
X107254Y366754D01*
X107445Y367064D01*
X107484Y367374D01*
X107407Y367736D01*
X107139Y367994D01*
X106870Y368097D01*
X106525D01*
G01X106870D02*
X107100Y368252D01*
X107292Y368511D01*
X107369Y368821D01*
X107292Y369131D01*
X107100Y369389D01*
X106755Y369544D01*
X106410Y369492D01*
X106065Y369286D01*
G01X108974Y369027D02*
X109204Y369337D01*
X109472Y369492D01*
X109779Y369544D01*
X110162Y369441D01*
X110430Y369182D01*
X110507Y368872D01*
X110469Y368562D01*
X110315Y368304D01*
X109549Y367787D01*
X109204Y367426D01*
X108974Y366909D01*
X108897Y366444D01*
X110507D01*
G01X148326Y694055D02*
X111514D01*
Y348149D01*
X148326D01*
Y694055D01*
G01X118621Y403288D02*
Y351122D01*
G01D02*
X418149D01*
G01X98993Y392820D02*
X105193D01*
Y389620D01*
X98993D01*
Y392820D01*
G01Y378180D02*
X105193D01*
Y374980D01*
X98993D01*
Y378180D01*
G01Y387835D02*
X105193D01*
Y384635D01*
X98993D01*
Y387835D01*
G01Y382986D02*
X105193D01*
Y379786D01*
X98993D01*
Y382986D01*
G01Y373509D02*
X105193D01*
Y370309D01*
X98993D01*
Y373509D01*
G01Y397624D02*
X105193D01*
Y394424D01*
X98993D01*
Y397624D01*
G01X104889Y411907D02*
X101789D01*
Y412866D01*
X101944Y413172D01*
X102151Y413364D01*
X102564Y413441D01*
X102977Y413364D01*
X103236Y413134D01*
X103391Y412866D01*
Y411907D01*
G01Y412866D02*
X104889Y413441D01*
G01Y415774D02*
X101789D01*
X102409Y415314D01*
G01X104889D02*
Y416234D01*
G01Y418874D02*
X101789D01*
X102409Y418414D01*
G01X104889D02*
Y419334D01*
G01Y421897D02*
X104217Y421974D01*
X103649Y422089D01*
X103132Y422242D01*
X102564Y422434D01*
X101789Y422741D01*
Y421207D01*
G01X99269Y401952D02*
X105469D01*
Y398752D01*
X99269D01*
Y401952D01*
G01X418149Y403288D02*
X118621D01*
G01X102993Y427704D02*
X109193D01*
Y424504D01*
X102993D01*
Y427704D01*
G01X104494Y429603D02*
X101394D01*
Y430562D01*
X101549Y430868D01*
X101756Y431060D01*
X102169Y431137D01*
X102582Y431060D01*
X102841Y430830D01*
X102996Y430562D01*
Y429603D01*
G01Y430562D02*
X104494Y431137D01*
G01X104132Y432818D02*
X104391Y433087D01*
X104494Y433393D01*
X104391Y433700D01*
X104081Y433968D01*
X103616Y434160D01*
X103151Y434237D01*
X102582D01*
X102117Y434160D01*
X101704Y433968D01*
X101497Y433738D01*
X101394Y433470D01*
X101497Y433163D01*
X101704Y432933D01*
X102014Y432780D01*
X102427Y432703D01*
X102789Y432780D01*
X103151Y432972D01*
X103357Y433202D01*
X103409Y433470D01*
X103306Y433777D01*
X103047Y434007D01*
X102582Y434237D01*
G01X103874Y435727D02*
X104236Y435957D01*
X104442Y436263D01*
X104494Y436608D01*
X104442Y436915D01*
X104184Y437222D01*
X103874Y437413D01*
X103564Y437452D01*
X103202Y437375D01*
X102944Y437107D01*
X102841Y436838D01*
Y436493D01*
G01Y436838D02*
X102686Y437068D01*
X102427Y437260D01*
X102117Y437337D01*
X101807Y437260D01*
X101549Y437068D01*
X101394Y436723D01*
X101446Y436378D01*
X101652Y436033D01*
G01X109268Y430779D02*
Y424579D01*
X106068D01*
Y430779D01*
X109268D01*
G01X106068Y421429D02*
Y427629D01*
X109268D01*
Y421429D01*
X106068D01*
G01X118622Y578288D02*
Y526122D01*
G01D02*
X418150D01*
G01Y578288D02*
X118622D01*
G01X108259Y679814D02*
Y682914D01*
X107799Y682294D01*
G01Y679814D02*
X108719D01*
G01X148326Y1042087D02*
X111514D01*
Y696181D01*
X148326D01*
Y1042087D01*
G01X118622Y753288D02*
Y701122D01*
G01D02*
X418150D01*
G01X105807Y710153D02*
X106037Y709791D01*
X106343Y709585D01*
X106688Y709533D01*
X106995Y709585D01*
X107302Y709843D01*
X107493Y710153D01*
X107532Y710463D01*
X107455Y710825D01*
X107187Y711083D01*
X106918Y711186D01*
X106573D01*
G01X106918D02*
X107148Y711341D01*
X107340Y711600D01*
X107417Y711910D01*
X107340Y712220D01*
X107148Y712478D01*
X106803Y712633D01*
X106458Y712581D01*
X106113Y712375D01*
G01X109022Y712116D02*
X109252Y712426D01*
X109520Y712581D01*
X109827Y712633D01*
X110210Y712530D01*
X110478Y712271D01*
X110555Y711961D01*
X110517Y711651D01*
X110363Y711393D01*
X109597Y710876D01*
X109252Y710515D01*
X109022Y709998D01*
X108945Y709533D01*
X110555D01*
G01X99531Y722345D02*
X105731D01*
Y719145D01*
X99531D01*
Y722345D01*
G01Y731998D02*
X105731D01*
Y728798D01*
X99531D01*
Y731998D01*
G01Y727057D02*
X105731D01*
Y723857D01*
X99531D01*
Y727057D01*
G01Y717537D02*
X105731D01*
Y714337D01*
X99531D01*
Y717537D01*
G01X105871Y743539D02*
X99671D01*
Y746739D01*
X105871D01*
Y743539D01*
G01X99531Y736848D02*
X105731D01*
Y733648D01*
X99531D01*
Y736848D01*
G01Y741562D02*
X105731D01*
Y738362D01*
X99531D01*
Y741562D01*
G01X99995Y751081D02*
X106195D01*
Y747881D01*
X99995D01*
Y751081D01*
G01X418150Y753288D02*
X118622D01*
G01X102917Y775700D02*
X109117D01*
Y772500D01*
X102917D01*
Y775700D01*
G01X108753Y780600D02*
X105653D01*
Y781559D01*
X105808Y781865D01*
X106015Y782057D01*
X106428Y782134D01*
X106841Y782057D01*
X107100Y781827D01*
X107255Y781559D01*
Y780600D01*
G01Y781559D02*
X108753Y782134D01*
G01X108391Y783815D02*
X108650Y784084D01*
X108753Y784390D01*
X108650Y784697D01*
X108340Y784965D01*
X107875Y785157D01*
X107410Y785234D01*
X106841D01*
X106376Y785157D01*
X105963Y784965D01*
X105756Y784735D01*
X105653Y784467D01*
X105756Y784160D01*
X105963Y783930D01*
X106273Y783777D01*
X106686Y783700D01*
X107048Y783777D01*
X107410Y783969D01*
X107616Y784199D01*
X107668Y784467D01*
X107565Y784774D01*
X107306Y785004D01*
X106841Y785234D01*
G01X108753Y787490D02*
X108081Y787567D01*
X107513Y787682D01*
X106996Y787835D01*
X106428Y788027D01*
X105653Y788334D01*
Y786800D01*
G01X109215Y778824D02*
Y772624D01*
X106015D01*
Y778824D01*
X109215D01*
G01X109065Y757848D02*
X105965D01*
Y758807D01*
X106120Y759113D01*
X106327Y759305D01*
X106740Y759382D01*
X107153Y759305D01*
X107412Y759075D01*
X107567Y758807D01*
Y757848D01*
G01Y758807D02*
X109065Y759382D01*
G01Y761715D02*
X105965D01*
X106585Y761255D01*
G01X109065D02*
Y762175D01*
G01X106482Y764087D02*
X106172Y764317D01*
X106017Y764585D01*
X105965Y764892D01*
X106068Y765275D01*
X106327Y765543D01*
X106637Y765620D01*
X106947Y765582D01*
X107205Y765428D01*
X107722Y764662D01*
X108083Y764317D01*
X108600Y764087D01*
X109065Y764010D01*
Y765620D01*
G01Y767915D02*
X105965D01*
X106585Y767455D01*
G01X109065D02*
Y768375D01*
G01X106017Y769476D02*
Y775676D01*
X109217D01*
Y769476D01*
X106017D01*
G01X118621Y928288D02*
Y876122D01*
G01D02*
X418149D01*
G01Y928288D02*
X118621D01*
G01X103950Y1000737D02*
X104142Y1000427D01*
X104372Y1000220D01*
X104640Y1000117D01*
X104947Y1000220D01*
X105177Y1000427D01*
X105407Y1000737D01*
X105484Y1001150D01*
Y1003217D01*
G01X106974Y1000737D02*
X107204Y1000375D01*
X107510Y1000169D01*
X107855Y1000117D01*
X108162Y1000169D01*
X108469Y1000427D01*
X108660Y1000737D01*
X108699Y1001047D01*
X108622Y1001409D01*
X108354Y1001667D01*
X108085Y1001770D01*
X107740D01*
G01X108085D02*
X108315Y1001925D01*
X108507Y1002184D01*
X108584Y1002494D01*
X108507Y1002804D01*
X108315Y1003062D01*
X107970Y1003217D01*
X107625Y1003165D01*
X107280Y1002959D01*
G01X108889Y1025931D02*
Y1029031D01*
X108429Y1028411D01*
G01Y1025931D02*
X109349D01*
G01X148326Y1390118D02*
X111514D01*
Y1044212D01*
X148326D01*
Y1390118D01*
G01X105142Y1060484D02*
X105372Y1060122D01*
X105678Y1059916D01*
X106023Y1059864D01*
X106330Y1059916D01*
X106637Y1060174D01*
X106828Y1060484D01*
X106867Y1060794D01*
X106790Y1061156D01*
X106522Y1061414D01*
X106253Y1061517D01*
X105908D01*
G01X106253D02*
X106483Y1061672D01*
X106675Y1061931D01*
X106752Y1062241D01*
X106675Y1062551D01*
X106483Y1062809D01*
X106138Y1062964D01*
X105793Y1062912D01*
X105448Y1062706D01*
G01X108357Y1062447D02*
X108587Y1062757D01*
X108855Y1062912D01*
X109162Y1062964D01*
X109545Y1062861D01*
X109813Y1062602D01*
X109890Y1062292D01*
X109852Y1061982D01*
X109698Y1061724D01*
X108932Y1061207D01*
X108587Y1060846D01*
X108357Y1060329D01*
X108280Y1059864D01*
X109890D01*
G01X99664Y1069115D02*
X105864D01*
Y1065915D01*
X99664D01*
Y1069115D01*
G01X118621Y1103288D02*
Y1051122D01*
G01D02*
X418149D01*
G01X99664Y1093636D02*
X105864D01*
Y1090436D01*
X99664D01*
Y1093636D01*
G01Y1073826D02*
X105864D01*
Y1070626D01*
X99664D01*
Y1073826D01*
G01Y1083391D02*
X105864D01*
Y1080191D01*
X99664D01*
Y1083391D01*
G01Y1078501D02*
X105864D01*
Y1075301D01*
X99664D01*
Y1078501D01*
G01Y1088695D02*
X105864D01*
Y1085495D01*
X99664D01*
Y1088695D01*
G01X105957Y1094803D02*
X99757D01*
Y1098003D01*
X105957D01*
Y1094803D01*
G01X103704Y1105878D02*
X100604D01*
Y1106837D01*
X100759Y1107143D01*
X100966Y1107335D01*
X101379Y1107412D01*
X101792Y1107335D01*
X102051Y1107105D01*
X102206Y1106837D01*
Y1105878D01*
G01Y1106837D02*
X103704Y1107412D01*
G01Y1109745D02*
X100604D01*
X101224Y1109285D01*
G01X103704D02*
Y1110205D01*
G01X101121Y1112117D02*
X100811Y1112347D01*
X100656Y1112615D01*
X100604Y1112922D01*
X100707Y1113305D01*
X100966Y1113573D01*
X101276Y1113650D01*
X101586Y1113612D01*
X101844Y1113458D01*
X102361Y1112692D01*
X102722Y1112347D01*
X103239Y1112117D01*
X103704Y1112040D01*
Y1113650D01*
G01X103239Y1115102D02*
X103497Y1115332D01*
X103652Y1115600D01*
X103704Y1115945D01*
X103601Y1116290D01*
X103394Y1116558D01*
X103032Y1116750D01*
X102619Y1116788D01*
X102206Y1116712D01*
X101947Y1116520D01*
X101741Y1116252D01*
X101689Y1115983D01*
X101741Y1115715D01*
X101947Y1115370D01*
X100604Y1115485D01*
Y1116520D01*
G01X107219Y1117490D02*
Y1123690D01*
X110419D01*
Y1117490D01*
X107219D01*
G01X104355Y1104135D02*
X110555D01*
Y1100935D01*
X104355D01*
Y1104135D01*
G01X418149Y1103288D02*
X118621D01*
G01X104159Y1123766D02*
X110359D01*
Y1120566D01*
X104159D01*
Y1123766D01*
G01X105349Y1130022D02*
X102249D01*
Y1130981D01*
X102404Y1131287D01*
X102611Y1131479D01*
X103024Y1131556D01*
X103437Y1131479D01*
X103696Y1131249D01*
X103851Y1130981D01*
Y1130022D01*
G01Y1130981D02*
X105349Y1131556D01*
G01Y1133889D02*
X102249D01*
X102869Y1133429D01*
G01X105349D02*
Y1134349D01*
G01X102249Y1136989D02*
X102352Y1136682D01*
X102611Y1136452D01*
X102921Y1136299D01*
X103334Y1136184D01*
X103799Y1136146D01*
X104264Y1136184D01*
X104677Y1136299D01*
X104987Y1136452D01*
X105246Y1136682D01*
X105349Y1136989D01*
X105246Y1137296D01*
X104987Y1137526D01*
X104677Y1137679D01*
X104264Y1137794D01*
X103799Y1137832D01*
X103334Y1137794D01*
X102921Y1137679D01*
X102611Y1137526D01*
X102352Y1137296D01*
X102249Y1136989D01*
G01X104987Y1139437D02*
X105246Y1139706D01*
X105349Y1140012D01*
X105246Y1140319D01*
X104936Y1140587D01*
X104471Y1140779D01*
X104006Y1140856D01*
X103437D01*
X102972Y1140779D01*
X102559Y1140587D01*
X102352Y1140357D01*
X102249Y1140089D01*
X102352Y1139782D01*
X102559Y1139552D01*
X102869Y1139399D01*
X103282Y1139322D01*
X103644Y1139399D01*
X104006Y1139591D01*
X104212Y1139821D01*
X104264Y1140089D01*
X104161Y1140396D01*
X103902Y1140626D01*
X103437Y1140856D01*
G01X110416Y1126838D02*
Y1120638D01*
X107216D01*
Y1126838D01*
X110416D01*
G01X118621Y1278288D02*
Y1226122D01*
G01D02*
X418149D01*
G01Y1278288D02*
X118621D01*
G01X108081Y1374958D02*
Y1378058D01*
X107621Y1377438D01*
G01Y1374958D02*
X108541D01*
G01X105835Y1408995D02*
X106065Y1408633D01*
X106371Y1408427D01*
X106716Y1408375D01*
X107023Y1408427D01*
X107330Y1408685D01*
X107521Y1408995D01*
X107560Y1409305D01*
X107483Y1409667D01*
X107215Y1409925D01*
X106946Y1410028D01*
X106601D01*
G01X106946D02*
X107176Y1410183D01*
X107368Y1410442D01*
X107445Y1410752D01*
X107368Y1411062D01*
X107176Y1411320D01*
X106831Y1411475D01*
X106486Y1411423D01*
X106141Y1411217D01*
G01X109050Y1410958D02*
X109280Y1411268D01*
X109548Y1411423D01*
X109855Y1411475D01*
X110238Y1411372D01*
X110506Y1411113D01*
X110583Y1410803D01*
X110545Y1410493D01*
X110391Y1410235D01*
X109625Y1409718D01*
X109280Y1409357D01*
X109050Y1408840D01*
X108973Y1408375D01*
X110583D01*
G01X148326Y1738150D02*
X111514D01*
Y1392244D01*
X148326D01*
Y1738150D01*
G01X118621Y1453288D02*
Y1401122D01*
G01D02*
X418149D01*
G01X98702Y1421092D02*
X104902D01*
Y1417892D01*
X98702D01*
Y1421092D01*
G01Y1435641D02*
X104902D01*
Y1432441D01*
X98702D01*
Y1435641D01*
G01Y1430795D02*
X104902D01*
Y1427595D01*
X98702D01*
Y1430795D01*
G01Y1425940D02*
X104902D01*
Y1422740D01*
X98702D01*
Y1425940D01*
G01X104968Y1446319D02*
X98768D01*
Y1449519D01*
X104968D01*
Y1446319D01*
G01X98702Y1445343D02*
X104902D01*
Y1442143D01*
X98702D01*
Y1445343D01*
G01Y1440580D02*
X104902D01*
Y1437380D01*
X98702D01*
Y1440580D01*
G01X106296Y1456832D02*
X103196D01*
Y1457791D01*
X103351Y1458097D01*
X103558Y1458289D01*
X103971Y1458366D01*
X104384Y1458289D01*
X104643Y1458059D01*
X104798Y1457791D01*
Y1456832D01*
G01Y1457791D02*
X106296Y1458366D01*
G01Y1460699D02*
X103196D01*
X103816Y1460239D01*
G01X106296D02*
Y1461159D01*
G01X103713Y1463071D02*
X103403Y1463301D01*
X103248Y1463569D01*
X103196Y1463876D01*
X103299Y1464259D01*
X103558Y1464527D01*
X103868Y1464604D01*
X104178Y1464566D01*
X104436Y1464412D01*
X104953Y1463646D01*
X105314Y1463301D01*
X105831Y1463071D01*
X106296Y1462994D01*
Y1464604D01*
G01X105934Y1466247D02*
X106193Y1466516D01*
X106296Y1466822D01*
X106193Y1467129D01*
X105883Y1467397D01*
X105418Y1467589D01*
X104953Y1467666D01*
X104384D01*
X103919Y1467589D01*
X103506Y1467397D01*
X103299Y1467167D01*
X103196Y1466899D01*
X103299Y1466592D01*
X103506Y1466362D01*
X103816Y1466209D01*
X104229Y1466132D01*
X104591Y1466209D01*
X104953Y1466401D01*
X105159Y1466631D01*
X105211Y1466899D01*
X105108Y1467206D01*
X104849Y1467436D01*
X104384Y1467666D01*
G01X98494Y1454731D02*
X104694D01*
Y1451531D01*
X98494D01*
Y1454731D01*
G01X418149Y1453288D02*
X118621D01*
G01X103865Y1471805D02*
X110065D01*
Y1468605D01*
X103865D01*
Y1471805D01*
G01X104777Y1478027D02*
X101677D01*
Y1478986D01*
X101832Y1479292D01*
X102039Y1479484D01*
X102452Y1479561D01*
X102865Y1479484D01*
X103124Y1479254D01*
X103279Y1478986D01*
Y1478027D01*
G01Y1478986D02*
X104777Y1479561D01*
G01Y1481894D02*
X101677D01*
X102297Y1481434D01*
G01X104777D02*
Y1482354D01*
G01X101677Y1484994D02*
X101780Y1484687D01*
X102039Y1484457D01*
X102349Y1484304D01*
X102762Y1484189D01*
X103227Y1484151D01*
X103692Y1484189D01*
X104105Y1484304D01*
X104415Y1484457D01*
X104674Y1484687D01*
X104777Y1484994D01*
X104674Y1485301D01*
X104415Y1485531D01*
X104105Y1485684D01*
X103692Y1485799D01*
X103227Y1485837D01*
X102762Y1485799D01*
X102349Y1485684D01*
X102039Y1485531D01*
X101780Y1485301D01*
X101677Y1484994D01*
G01X104312Y1487251D02*
X104570Y1487481D01*
X104725Y1487749D01*
X104777Y1488094D01*
X104674Y1488439D01*
X104467Y1488707D01*
X104105Y1488899D01*
X103692Y1488937D01*
X103279Y1488861D01*
X103020Y1488669D01*
X102814Y1488401D01*
X102762Y1488132D01*
X102814Y1487864D01*
X103020Y1487519D01*
X101677Y1487634D01*
Y1488669D01*
G01X110173Y1474882D02*
Y1468682D01*
X106973D01*
Y1474882D01*
X110173D01*
G01X106974Y1465532D02*
Y1471732D01*
X110174D01*
Y1465532D01*
X106974D01*
G01X118621Y1628288D02*
Y1576122D01*
G01D02*
X418149D01*
G01Y1628288D02*
X118621D01*
G01X107799Y1722973D02*
Y1726073D01*
X107339Y1725453D01*
G01Y1722973D02*
X108259D01*
G01X103758Y1730344D02*
X103950Y1730034D01*
X104180Y1729827D01*
X104448Y1729724D01*
X104755Y1729827D01*
X104985Y1730034D01*
X105215Y1730344D01*
X105292Y1730757D01*
Y1732824D01*
G01X106782Y1730189D02*
X107012Y1729931D01*
X107280Y1729776D01*
X107625Y1729724D01*
X107970Y1729827D01*
X108238Y1730034D01*
X108430Y1730396D01*
X108468Y1730809D01*
X108392Y1731222D01*
X108200Y1731481D01*
X107932Y1731687D01*
X107663Y1731739D01*
X107395Y1731687D01*
X107050Y1731481D01*
X107165Y1732824D01*
X108200D01*
G01X148326Y2086181D02*
X111514D01*
Y1740275D01*
X148326D01*
Y2086181D01*
G01X103630Y1752870D02*
X103860Y1752508D01*
X104166Y1752302D01*
X104511Y1752250D01*
X104818Y1752302D01*
X105125Y1752560D01*
X105316Y1752870D01*
X105355Y1753180D01*
X105278Y1753542D01*
X105010Y1753800D01*
X104741Y1753903D01*
X104396D01*
G01X104741D02*
X104971Y1754058D01*
X105163Y1754317D01*
X105240Y1754627D01*
X105163Y1754937D01*
X104971Y1755195D01*
X104626Y1755350D01*
X104281Y1755298D01*
X103936Y1755092D01*
G01X106845Y1754833D02*
X107075Y1755143D01*
X107343Y1755298D01*
X107650Y1755350D01*
X108033Y1755247D01*
X108301Y1754988D01*
X108378Y1754678D01*
X108340Y1754368D01*
X108186Y1754110D01*
X107420Y1753593D01*
X107075Y1753232D01*
X106845Y1752715D01*
X106768Y1752250D01*
X108378D01*
G01X100152Y1762427D02*
X106352D01*
Y1759227D01*
X100152D01*
Y1762427D01*
G01Y1772127D02*
X106352D01*
Y1768927D01*
X100152D01*
Y1772127D01*
G01Y1767322D02*
X106352D01*
Y1764122D01*
X100152D01*
Y1767322D01*
G01X118621Y1803288D02*
Y1751122D01*
G01D02*
X418149D01*
G01X106455Y1788347D02*
X100255D01*
Y1791547D01*
X106455D01*
Y1788347D01*
G01X100152Y1787171D02*
X106352D01*
Y1783971D01*
X100152D01*
Y1787171D01*
G01Y1777114D02*
X106352D01*
Y1773914D01*
X100152D01*
Y1777114D01*
G01Y1782142D02*
X106352D01*
Y1778942D01*
X100152D01*
Y1782142D01*
G01X104144Y1819828D02*
X110344D01*
Y1816628D01*
X104144D01*
Y1819828D01*
G01X110419Y1822903D02*
Y1816703D01*
X107219D01*
Y1822903D01*
X110419D01*
G01X104823Y1802876D02*
X101723D01*
Y1803835D01*
X101878Y1804141D01*
X102085Y1804333D01*
X102498Y1804410D01*
X102911Y1804333D01*
X103170Y1804103D01*
X103325Y1803835D01*
Y1802876D01*
G01Y1803835D02*
X104823Y1804410D01*
G01Y1806743D02*
X101723D01*
X102343Y1806283D01*
G01X104823D02*
Y1807203D01*
G01X104203Y1809000D02*
X104565Y1809230D01*
X104771Y1809536D01*
X104823Y1809881D01*
X104771Y1810188D01*
X104513Y1810495D01*
X104203Y1810686D01*
X103893Y1810725D01*
X103531Y1810648D01*
X103273Y1810380D01*
X103170Y1810111D01*
Y1809766D01*
G01Y1810111D02*
X103015Y1810341D01*
X102756Y1810533D01*
X102446Y1810610D01*
X102136Y1810533D01*
X101878Y1810341D01*
X101723Y1809996D01*
X101775Y1809651D01*
X101981Y1809306D01*
G01X104203Y1812100D02*
X104565Y1812330D01*
X104771Y1812636D01*
X104823Y1812981D01*
X104771Y1813288D01*
X104513Y1813595D01*
X104203Y1813786D01*
X103893Y1813825D01*
X103531Y1813748D01*
X103273Y1813480D01*
X103170Y1813211D01*
Y1812866D01*
G01Y1813211D02*
X103015Y1813441D01*
X102756Y1813633D01*
X102446Y1813710D01*
X102136Y1813633D01*
X101878Y1813441D01*
X101723Y1813096D01*
X101775Y1812751D01*
X101981Y1812406D01*
G01X107219Y1813553D02*
Y1819753D01*
X110419D01*
Y1813553D01*
X107219D01*
G01X102146Y1799824D02*
X108346D01*
Y1796624D01*
X102146D01*
Y1799824D01*
G01X418149Y1803288D02*
X118621D01*
G01X106138Y1825374D02*
X103038D01*
Y1826333D01*
X103193Y1826639D01*
X103400Y1826831D01*
X103813Y1826908D01*
X104226Y1826831D01*
X104485Y1826601D01*
X104640Y1826333D01*
Y1825374D01*
G01Y1826333D02*
X106138Y1826908D01*
G01Y1829241D02*
X103038D01*
X103658Y1828781D01*
G01X106138D02*
Y1829701D01*
G01X103038Y1832341D02*
X103141Y1832034D01*
X103400Y1831804D01*
X103710Y1831651D01*
X104123Y1831536D01*
X104588Y1831498D01*
X105053Y1831536D01*
X105466Y1831651D01*
X105776Y1831804D01*
X106035Y1832034D01*
X106138Y1832341D01*
X106035Y1832648D01*
X105776Y1832878D01*
X105466Y1833031D01*
X105053Y1833146D01*
X104588Y1833184D01*
X104123Y1833146D01*
X103710Y1833031D01*
X103400Y1832878D01*
X103141Y1832648D01*
X103038Y1832341D01*
G01X106138Y1835441D02*
X103038D01*
X103658Y1834981D01*
G01X106138D02*
Y1835901D01*
G01X118621Y1978288D02*
Y1926122D01*
G01D02*
X418149D01*
G01Y1978288D02*
X118621D01*
G01X108784Y2070877D02*
Y2073977D01*
X108324Y2073357D01*
G01Y2070877D02*
X109244D01*
G01X150047Y19336D02*
X150277Y18974D01*
X150583Y18768D01*
X150928Y18716D01*
X151235Y18768D01*
X151542Y19026D01*
X151733Y19336D01*
X151772Y19646D01*
X151695Y20008D01*
X151427Y20266D01*
X151158Y20369D01*
X150813D01*
G01X151158D02*
X151388Y20524D01*
X151580Y20783D01*
X151657Y21093D01*
X151580Y21403D01*
X151388Y21661D01*
X151043Y21816D01*
X150698Y21764D01*
X150353Y21558D01*
G01X153147Y19336D02*
X153377Y18974D01*
X153683Y18768D01*
X154028Y18716D01*
X154335Y18768D01*
X154642Y19026D01*
X154833Y19336D01*
X154872Y19646D01*
X154795Y20008D01*
X154527Y20266D01*
X154258Y20369D01*
X153913D01*
G01X154258D02*
X154488Y20524D01*
X154680Y20783D01*
X154757Y21093D01*
X154680Y21403D01*
X154488Y21661D01*
X154143Y21816D01*
X153798Y21764D01*
X153453Y21558D01*
G01X169714Y13915D02*
Y17015D01*
X170634D01*
X170941Y16860D01*
X171171Y16498D01*
X171248Y16085D01*
X171171Y15672D01*
X170979Y15362D01*
X170634Y15207D01*
X169714D01*
G01X172738Y14535D02*
X172968Y14173D01*
X173274Y13967D01*
X173619Y13915D01*
X173926Y13967D01*
X174233Y14225D01*
X174424Y14535D01*
X174463Y14845D01*
X174386Y15207D01*
X174118Y15465D01*
X173849Y15568D01*
X173504D01*
G01X173849D02*
X174079Y15723D01*
X174271Y15982D01*
X174348Y16292D01*
X174271Y16602D01*
X174079Y16860D01*
X173734Y17015D01*
X173389Y16963D01*
X173044Y16757D01*
G01X175953Y16498D02*
X176183Y16808D01*
X176451Y16963D01*
X176758Y17015D01*
X177141Y16912D01*
X177409Y16653D01*
X177486Y16343D01*
X177448Y16033D01*
X177294Y15775D01*
X176528Y15258D01*
X176183Y14897D01*
X175953Y14380D01*
X175876Y13915D01*
X177486D01*
G01X161201Y55144D02*
X155001D01*
Y58344D01*
X161201D01*
Y55144D01*
G01X164141Y66367D02*
Y69467D01*
X165100D01*
X165406Y69312D01*
X165598Y69105D01*
X165675Y68692D01*
X165598Y68279D01*
X165368Y68020D01*
X165100Y67865D01*
X164141D01*
G01X165100D02*
X165675Y66367D01*
G01X168008D02*
Y69467D01*
X167548Y68847D01*
G01Y66367D02*
X168468D01*
G01X170380Y68950D02*
X170610Y69260D01*
X170878Y69415D01*
X171185Y69467D01*
X171568Y69364D01*
X171836Y69105D01*
X171913Y68795D01*
X171875Y68485D01*
X171721Y68227D01*
X170955Y67710D01*
X170610Y67349D01*
X170380Y66832D01*
X170303Y66367D01*
X171913D01*
G01X159988Y66530D02*
X153788D01*
Y69730D01*
X159988D01*
Y66530D01*
G01X163707Y71041D02*
Y74141D01*
X164666D01*
X164972Y73986D01*
X165164Y73779D01*
X165241Y73366D01*
X165164Y72953D01*
X164934Y72694D01*
X164666Y72539D01*
X163707D01*
G01X164666D02*
X165241Y71041D01*
G01X168034D02*
Y74141D01*
X166616Y71919D01*
X168532D01*
G01X170674Y74141D02*
X170367Y74038D01*
X170137Y73779D01*
X169984Y73469D01*
X169869Y73056D01*
X169831Y72591D01*
X169869Y72126D01*
X169984Y71713D01*
X170137Y71403D01*
X170367Y71144D01*
X170674Y71041D01*
X170981Y71144D01*
X171211Y71403D01*
X171364Y71713D01*
X171479Y72126D01*
X171517Y72591D01*
X171479Y73056D01*
X171364Y73469D01*
X171211Y73779D01*
X170981Y74038D01*
X170674Y74141D01*
G01X153677Y74097D02*
X159877D01*
Y70897D01*
X153677D01*
Y74097D01*
G01X155543Y60131D02*
Y63231D01*
X156502D01*
X156808Y63076D01*
X157000Y62869D01*
X157077Y62456D01*
X157000Y62043D01*
X156770Y61784D01*
X156502Y61629D01*
X155543D01*
G01X156502D02*
X157077Y60131D01*
G01X158758Y60493D02*
X159027Y60234D01*
X159333Y60131D01*
X159640Y60234D01*
X159908Y60544D01*
X160100Y61009D01*
X160177Y61474D01*
Y62043D01*
X160100Y62508D01*
X159908Y62921D01*
X159678Y63128D01*
X159410Y63231D01*
X159103Y63128D01*
X158873Y62921D01*
X158720Y62611D01*
X158643Y62198D01*
X158720Y61836D01*
X158912Y61474D01*
X159142Y61268D01*
X159410Y61216D01*
X159717Y61319D01*
X159947Y61578D01*
X160177Y62043D01*
G01X166932Y87466D02*
Y90566D01*
X167891D01*
X168197Y90411D01*
X168389Y90204D01*
X168466Y89791D01*
X168389Y89378D01*
X168159Y89119D01*
X167891Y88964D01*
X166932D01*
G01X167891D02*
X168466Y87466D01*
G01X170799D02*
Y90566D01*
X170339Y89946D01*
G01Y87466D02*
X171259D01*
G01X160084Y86508D02*
X153884D01*
Y89708D01*
X160084D01*
Y86508D01*
G01X156864Y94116D02*
X153764D01*
Y95075D01*
X153919Y95381D01*
X154126Y95573D01*
X154539Y95650D01*
X154952Y95573D01*
X155211Y95343D01*
X155366Y95075D01*
Y94116D01*
G01Y95075D02*
X156864Y95650D01*
G01Y97983D02*
X156812Y98251D01*
X156657Y98558D01*
X156399Y98750D01*
X156037Y98826D01*
X155676Y98750D01*
X155366Y98520D01*
X155211Y98175D01*
Y97791D01*
X155107Y97561D01*
X154849Y97370D01*
X154487Y97293D01*
X154126Y97408D01*
X153867Y97676D01*
X153764Y97983D01*
X153867Y98290D01*
X154126Y98558D01*
X154487Y98673D01*
X154849Y98596D01*
X155107Y98405D01*
X155211Y98175D01*
Y97791D01*
X155366Y97446D01*
X155676Y97216D01*
X156037Y97140D01*
X156399Y97216D01*
X156657Y97408D01*
X156812Y97715D01*
X156864Y97983D01*
G01X155572Y100355D02*
X155211Y100623D01*
X155004Y100853D01*
X154901Y101160D01*
X155004Y101428D01*
X155211Y101620D01*
X155521Y101773D01*
X155882Y101811D01*
X156192Y101773D01*
X156502Y101620D01*
X156761Y101390D01*
X156864Y101121D01*
X156761Y100815D01*
X156451Y100546D01*
X155986Y100393D01*
X155469Y100355D01*
X154797Y100431D01*
X154436Y100546D01*
X154074Y100738D01*
X153816Y101006D01*
X153764Y101275D01*
X153867Y101543D01*
X154126Y101735D01*
G01X156970Y92806D02*
Y86606D01*
X153770D01*
Y92806D01*
X156970D01*
G01X161442Y82539D02*
Y85639D01*
X162401D01*
X162707Y85484D01*
X162899Y85277D01*
X162976Y84864D01*
X162899Y84451D01*
X162669Y84192D01*
X162401Y84037D01*
X161442D01*
G01X162401D02*
X162976Y82539D01*
G01X165309D02*
Y85639D01*
X164849Y85019D01*
G01Y82539D02*
X165769D01*
G01X168409D02*
Y85639D01*
X167949Y85019D01*
G01Y82539D02*
X168869D01*
G01X171509Y85639D02*
X171202Y85536D01*
X170972Y85277D01*
X170819Y84967D01*
X170704Y84554D01*
X170666Y84089D01*
X170704Y83624D01*
X170819Y83211D01*
X170972Y82901D01*
X171202Y82642D01*
X171509Y82539D01*
X171816Y82642D01*
X172046Y82901D01*
X172199Y83211D01*
X172314Y83624D01*
X172352Y84089D01*
X172314Y84554D01*
X172199Y84967D01*
X172046Y85277D01*
X171816Y85536D01*
X171509Y85639D01*
G01X153766Y83492D02*
Y89692D01*
X156966D01*
Y83492D01*
X153766D01*
G01X166075Y171126D02*
Y174226D01*
X166995D01*
X167302Y174071D01*
X167532Y173709D01*
X167609Y173296D01*
X167532Y172883D01*
X167340Y172573D01*
X166995Y172418D01*
X166075D01*
G01X169099Y171746D02*
X169329Y171384D01*
X169635Y171178D01*
X169980Y171126D01*
X170287Y171178D01*
X170594Y171436D01*
X170785Y171746D01*
X170824Y172056D01*
X170747Y172418D01*
X170479Y172676D01*
X170210Y172779D01*
X169865D01*
G01X170210D02*
X170440Y172934D01*
X170632Y173193D01*
X170709Y173503D01*
X170632Y173813D01*
X170440Y174071D01*
X170095Y174226D01*
X169750Y174174D01*
X169405Y173968D01*
G01X172314Y173709D02*
X172544Y174019D01*
X172812Y174174D01*
X173119Y174226D01*
X173502Y174123D01*
X173770Y173864D01*
X173847Y173554D01*
X173809Y173244D01*
X173655Y172986D01*
X172889Y172469D01*
X172544Y172108D01*
X172314Y171591D01*
X172237Y171126D01*
X173847D01*
G01X149901Y318042D02*
X150093Y317732D01*
X150323Y317525D01*
X150591Y317422D01*
X150898Y317525D01*
X151128Y317732D01*
X151358Y318042D01*
X151435Y318455D01*
Y320522D01*
G01X153768Y317422D02*
Y320522D01*
X153308Y319902D01*
G01Y317422D02*
X154228D01*
G01X150526Y328472D02*
X150794Y328833D01*
X151024Y329040D01*
X151331Y329143D01*
X151599Y329040D01*
X151791Y328833D01*
X151944Y328523D01*
X151982Y328162D01*
X151944Y327852D01*
X151791Y327542D01*
X151561Y327283D01*
X151292Y327180D01*
X150986Y327283D01*
X150717Y327593D01*
X150564Y328058D01*
X150526Y328575D01*
X150602Y329247D01*
X150717Y329608D01*
X150909Y329970D01*
X151177Y330228D01*
X151446Y330280D01*
X151714Y330177D01*
X151906Y329918D01*
G01X154814Y327180D02*
Y330280D01*
X153396Y328058D01*
X155312D01*
G01X168999Y345741D02*
Y348841D01*
X169919D01*
X170226Y348686D01*
X170456Y348324D01*
X170533Y347911D01*
X170456Y347498D01*
X170264Y347188D01*
X169919Y347033D01*
X168999D01*
G01X172023Y346361D02*
X172253Y345999D01*
X172559Y345793D01*
X172904Y345741D01*
X173211Y345793D01*
X173518Y346051D01*
X173709Y346361D01*
X173748Y346671D01*
X173671Y347033D01*
X173403Y347291D01*
X173134Y347394D01*
X172789D01*
G01X173134D02*
X173364Y347549D01*
X173556Y347808D01*
X173633Y348118D01*
X173556Y348428D01*
X173364Y348686D01*
X173019Y348841D01*
X172674Y348789D01*
X172329Y348583D01*
G01X175238Y348324D02*
X175468Y348634D01*
X175736Y348789D01*
X176043Y348841D01*
X176426Y348738D01*
X176694Y348479D01*
X176771Y348169D01*
X176733Y347859D01*
X176579Y347601D01*
X175813Y347084D01*
X175468Y346723D01*
X175238Y346206D01*
X175161Y345741D01*
X176771D01*
G01X150363Y347536D02*
X150593Y347174D01*
X150899Y346968D01*
X151244Y346916D01*
X151551Y346968D01*
X151858Y347226D01*
X152049Y347536D01*
X152088Y347846D01*
X152011Y348208D01*
X151743Y348466D01*
X151474Y348569D01*
X151129D01*
G01X151474D02*
X151704Y348724D01*
X151896Y348983D01*
X151973Y349293D01*
X151896Y349603D01*
X151704Y349861D01*
X151359Y350016D01*
X151014Y349964D01*
X150669Y349758D01*
G01X153463Y347536D02*
X153693Y347174D01*
X153999Y346968D01*
X154344Y346916D01*
X154651Y346968D01*
X154958Y347226D01*
X155149Y347536D01*
X155188Y347846D01*
X155111Y348208D01*
X154843Y348466D01*
X154574Y348569D01*
X154229D01*
G01X154574D02*
X154804Y348724D01*
X154996Y348983D01*
X155073Y349293D01*
X154996Y349603D01*
X154804Y349861D01*
X154459Y350016D01*
X154114Y349964D01*
X153769Y349758D01*
G01X167837Y413737D02*
X164737D01*
Y414696D01*
X164892Y415002D01*
X165099Y415194D01*
X165512Y415271D01*
X165925Y415194D01*
X166184Y414964D01*
X166339Y414696D01*
Y413737D01*
G01Y414696D02*
X167837Y415271D01*
G01Y418064D02*
X164737D01*
X166959Y416646D01*
Y418562D01*
G01X157921Y419723D02*
Y413523D01*
X154721D01*
Y419723D01*
X157921D01*
G01X163704Y406282D02*
Y409382D01*
X164663D01*
X164969Y409227D01*
X165161Y409020D01*
X165238Y408607D01*
X165161Y408194D01*
X164931Y407935D01*
X164663Y407780D01*
X163704D01*
G01X164663D02*
X165238Y406282D01*
G01X167571D02*
Y409382D01*
X167111Y408762D01*
G01Y406282D02*
X168031D01*
G01X170671D02*
Y409382D01*
X170211Y408762D01*
G01Y406282D02*
X171131D01*
G01X160015Y405975D02*
X153815D01*
Y409175D01*
X160015D01*
Y405975D01*
G01X172215Y413760D02*
X169115D01*
Y414719D01*
X169270Y415025D01*
X169477Y415217D01*
X169890Y415294D01*
X170303Y415217D01*
X170562Y414987D01*
X170717Y414719D01*
Y413760D01*
G01Y414719D02*
X172215Y415294D01*
G01Y417627D02*
X172163Y417895D01*
X172008Y418202D01*
X171750Y418394D01*
X171388Y418470D01*
X171027Y418394D01*
X170717Y418164D01*
X170562Y417819D01*
Y417435D01*
X170458Y417205D01*
X170200Y417014D01*
X169838Y416937D01*
X169477Y417052D01*
X169218Y417320D01*
X169115Y417627D01*
X169218Y417934D01*
X169477Y418202D01*
X169838Y418317D01*
X170200Y418240D01*
X170458Y418049D01*
X170562Y417819D01*
Y417435D01*
X170717Y417090D01*
X171027Y416860D01*
X171388Y416784D01*
X171750Y416860D01*
X172008Y417052D01*
X172163Y417359D01*
X172215Y417627D01*
G01X162856Y419720D02*
Y413520D01*
X159656D01*
Y419720D01*
X162856D01*
G01X163710Y437317D02*
Y440417D01*
X164669D01*
X164975Y440262D01*
X165167Y440055D01*
X165244Y439642D01*
X165167Y439229D01*
X164937Y438970D01*
X164669Y438815D01*
X163710D01*
G01X164669D02*
X165244Y437317D01*
G01X166734Y437937D02*
X166964Y437575D01*
X167270Y437369D01*
X167615Y437317D01*
X167922Y437369D01*
X168229Y437627D01*
X168420Y437937D01*
X168459Y438247D01*
X168382Y438609D01*
X168114Y438867D01*
X167845Y438970D01*
X167500D01*
G01X167845D02*
X168075Y439125D01*
X168267Y439384D01*
X168344Y439694D01*
X168267Y440004D01*
X168075Y440262D01*
X167730Y440417D01*
X167385Y440365D01*
X167040Y440159D01*
G01X160023Y434519D02*
X153823D01*
Y437719D01*
X160023D01*
Y434519D01*
G01X156846Y442424D02*
X153746D01*
Y443383D01*
X153901Y443689D01*
X154108Y443881D01*
X154521Y443958D01*
X154934Y443881D01*
X155193Y443651D01*
X155348Y443383D01*
Y442424D01*
G01Y443383D02*
X156846Y443958D01*
G01X156484Y445639D02*
X156743Y445908D01*
X156846Y446214D01*
X156743Y446521D01*
X156433Y446789D01*
X155968Y446981D01*
X155503Y447058D01*
X154934D01*
X154469Y446981D01*
X154056Y446789D01*
X153849Y446559D01*
X153746Y446291D01*
X153849Y445984D01*
X154056Y445754D01*
X154366Y445601D01*
X154779Y445524D01*
X155141Y445601D01*
X155503Y445793D01*
X155709Y446023D01*
X155761Y446291D01*
X155658Y446598D01*
X155399Y446828D01*
X154934Y447058D01*
G01X153746Y449391D02*
X153849Y449084D01*
X154108Y448854D01*
X154418Y448701D01*
X154831Y448586D01*
X155296Y448548D01*
X155761Y448586D01*
X156174Y448701D01*
X156484Y448854D01*
X156743Y449084D01*
X156846Y449391D01*
X156743Y449698D01*
X156484Y449928D01*
X156174Y450081D01*
X155761Y450196D01*
X155296Y450234D01*
X154831Y450196D01*
X154418Y450081D01*
X154108Y449928D01*
X153849Y449698D01*
X153746Y449391D01*
G01X156951Y440793D02*
Y434593D01*
X153751D01*
Y440793D01*
X156951D01*
G01X165205Y424287D02*
X162105D01*
Y425246D01*
X162260Y425552D01*
X162467Y425744D01*
X162880Y425821D01*
X163293Y425744D01*
X163552Y425514D01*
X163707Y425246D01*
Y424287D01*
G01Y425246D02*
X165205Y425821D01*
G01Y428154D02*
X162105D01*
X162725Y427694D01*
G01X165205D02*
Y428614D01*
G01Y431254D02*
X162105D01*
X162725Y430794D01*
G01X165205D02*
Y431714D01*
G01Y434814D02*
X162105D01*
X164327Y433396D01*
Y435312D01*
G01X153748Y431444D02*
Y437644D01*
X156948D01*
Y431444D01*
X153748D01*
G01X168846Y519413D02*
Y522513D01*
X169766D01*
X170073Y522358D01*
X170303Y521996D01*
X170380Y521583D01*
X170303Y521170D01*
X170111Y520860D01*
X169766Y520705D01*
X168846D01*
G01X171870Y520033D02*
X172100Y519671D01*
X172406Y519465D01*
X172751Y519413D01*
X173058Y519465D01*
X173365Y519723D01*
X173556Y520033D01*
X173595Y520343D01*
X173518Y520705D01*
X173250Y520963D01*
X172981Y521066D01*
X172636D01*
G01X172981D02*
X173211Y521221D01*
X173403Y521480D01*
X173480Y521790D01*
X173403Y522100D01*
X173211Y522358D01*
X172866Y522513D01*
X172521Y522461D01*
X172176Y522255D01*
G01X175085Y521996D02*
X175315Y522306D01*
X175583Y522461D01*
X175890Y522513D01*
X176273Y522410D01*
X176541Y522151D01*
X176618Y521841D01*
X176580Y521531D01*
X176426Y521273D01*
X175660Y520756D01*
X175315Y520395D01*
X175085Y519878D01*
X175008Y519413D01*
X176618D01*
G01X168291Y581251D02*
Y584351D01*
X169211D01*
X169518Y584196D01*
X169748Y583834D01*
X169825Y583421D01*
X169748Y583008D01*
X169556Y582698D01*
X169211Y582543D01*
X168291D01*
G01X172158Y581251D02*
Y584351D01*
X171698Y583731D01*
G01Y581251D02*
X172618D01*
G01X150373Y663045D02*
X150565Y662735D01*
X150795Y662528D01*
X151063Y662425D01*
X151370Y662528D01*
X151600Y662735D01*
X151830Y663045D01*
X151907Y663458D01*
Y665525D01*
G01X153512Y665008D02*
X153742Y665318D01*
X154010Y665473D01*
X154317Y665525D01*
X154700Y665422D01*
X154968Y665163D01*
X155045Y664853D01*
X155007Y664543D01*
X154853Y664285D01*
X154087Y663768D01*
X153742Y663407D01*
X153512Y662890D01*
X153435Y662425D01*
X155045D01*
G01X150421Y678772D02*
X150689Y679133D01*
X150919Y679340D01*
X151226Y679443D01*
X151494Y679340D01*
X151686Y679133D01*
X151839Y678823D01*
X151877Y678462D01*
X151839Y678152D01*
X151686Y677842D01*
X151456Y677583D01*
X151187Y677480D01*
X150881Y677583D01*
X150612Y677893D01*
X150459Y678358D01*
X150421Y678875D01*
X150497Y679547D01*
X150612Y679908D01*
X150804Y680270D01*
X151072Y680528D01*
X151341Y680580D01*
X151609Y680477D01*
X151801Y680218D01*
G01X154709Y677480D02*
Y680580D01*
X153291Y678358D01*
X155207D01*
G01X150466Y697320D02*
X150696Y696958D01*
X151002Y696752D01*
X151347Y696700D01*
X151654Y696752D01*
X151961Y697010D01*
X152152Y697320D01*
X152191Y697630D01*
X152114Y697992D01*
X151846Y698250D01*
X151577Y698353D01*
X151232D01*
G01X151577D02*
X151807Y698508D01*
X151999Y698767D01*
X152076Y699077D01*
X151999Y699387D01*
X151807Y699645D01*
X151462Y699800D01*
X151117Y699748D01*
X150772Y699542D01*
G01X153566Y697320D02*
X153796Y696958D01*
X154102Y696752D01*
X154447Y696700D01*
X154754Y696752D01*
X155061Y697010D01*
X155252Y697320D01*
X155291Y697630D01*
X155214Y697992D01*
X154946Y698250D01*
X154677Y698353D01*
X154332D01*
G01X154677D02*
X154907Y698508D01*
X155099Y698767D01*
X155176Y699077D01*
X155099Y699387D01*
X154907Y699645D01*
X154562Y699800D01*
X154217Y699748D01*
X153872Y699542D01*
G01X169591Y715062D02*
Y718162D01*
X170511D01*
X170818Y718007D01*
X171048Y717645D01*
X171125Y717232D01*
X171048Y716819D01*
X170856Y716509D01*
X170511Y716354D01*
X169591D01*
G01X172615Y715682D02*
X172845Y715320D01*
X173151Y715114D01*
X173496Y715062D01*
X173803Y715114D01*
X174110Y715372D01*
X174301Y715682D01*
X174340Y715992D01*
X174263Y716354D01*
X173995Y716612D01*
X173726Y716715D01*
X173381D01*
G01X173726D02*
X173956Y716870D01*
X174148Y717129D01*
X174225Y717439D01*
X174148Y717749D01*
X173956Y718007D01*
X173611Y718162D01*
X173266Y718110D01*
X172921Y717904D01*
G01X175830Y717645D02*
X176060Y717955D01*
X176328Y718110D01*
X176635Y718162D01*
X177018Y718059D01*
X177286Y717800D01*
X177363Y717490D01*
X177325Y717180D01*
X177171Y716922D01*
X176405Y716405D01*
X176060Y716044D01*
X175830Y715527D01*
X175753Y715062D01*
X177363D01*
G01X164162Y755043D02*
Y758143D01*
X165121D01*
X165427Y757988D01*
X165619Y757781D01*
X165696Y757368D01*
X165619Y756955D01*
X165389Y756696D01*
X165121Y756541D01*
X164162D01*
G01X165121D02*
X165696Y755043D01*
G01X168029D02*
Y758143D01*
X167569Y757523D01*
G01Y755043D02*
X168489D01*
G01X171129Y758143D02*
X170822Y758040D01*
X170592Y757781D01*
X170439Y757471D01*
X170324Y757058D01*
X170286Y756593D01*
X170324Y756128D01*
X170439Y755715D01*
X170592Y755405D01*
X170822Y755146D01*
X171129Y755043D01*
X171436Y755146D01*
X171666Y755405D01*
X171819Y755715D01*
X171934Y756128D01*
X171972Y756593D01*
X171934Y757058D01*
X171819Y757471D01*
X171666Y757781D01*
X171436Y758040D01*
X171129Y758143D01*
G01X160475Y755157D02*
X154275D01*
Y758357D01*
X160475D01*
Y755157D01*
G01X164206Y762500D02*
Y765600D01*
X165165D01*
X165471Y765445D01*
X165663Y765238D01*
X165740Y764825D01*
X165663Y764412D01*
X165433Y764153D01*
X165165Y763998D01*
X164206D01*
G01X165165D02*
X165740Y762500D01*
G01X168073D02*
Y765600D01*
X167613Y764980D01*
G01Y762500D02*
X168533D01*
G01X170330Y763120D02*
X170560Y762758D01*
X170866Y762552D01*
X171211Y762500D01*
X171518Y762552D01*
X171825Y762810D01*
X172016Y763120D01*
X172055Y763430D01*
X171978Y763792D01*
X171710Y764050D01*
X171441Y764153D01*
X171096D01*
G01X171441D02*
X171671Y764308D01*
X171863Y764567D01*
X171940Y764877D01*
X171863Y765187D01*
X171671Y765445D01*
X171326Y765600D01*
X170981Y765548D01*
X170636Y765342D01*
G01X160190Y762631D02*
X153990D01*
Y765831D01*
X160190D01*
Y762631D01*
G01X165063Y773963D02*
Y777063D01*
X166022D01*
X166328Y776908D01*
X166520Y776701D01*
X166597Y776288D01*
X166520Y775875D01*
X166290Y775616D01*
X166022Y775461D01*
X165063D01*
G01X166022D02*
X166597Y773963D01*
G01X169390D02*
Y777063D01*
X167972Y774841D01*
X169888D01*
G01X171302Y776546D02*
X171532Y776856D01*
X171800Y777011D01*
X172107Y777063D01*
X172490Y776960D01*
X172758Y776701D01*
X172835Y776391D01*
X172797Y776081D01*
X172643Y775823D01*
X171877Y775306D01*
X171532Y774945D01*
X171302Y774428D01*
X171225Y773963D01*
X172835D01*
G01X153588Y778273D02*
X159788D01*
Y775073D01*
X153588D01*
Y778273D01*
G01X163574Y779254D02*
Y782354D01*
X164533D01*
X164839Y782199D01*
X165031Y781992D01*
X165108Y781579D01*
X165031Y781166D01*
X164801Y780907D01*
X164533Y780752D01*
X163574D01*
G01X164533D02*
X165108Y779254D01*
G01X167441D02*
Y782354D01*
X166981Y781734D01*
G01Y779254D02*
X167901D01*
G01X170541D02*
Y782354D01*
X170081Y781734D01*
G01Y779254D02*
X171001D01*
G01X173641D02*
X173909Y779306D01*
X174216Y779461D01*
X174408Y779719D01*
X174484Y780081D01*
X174408Y780442D01*
X174178Y780752D01*
X173833Y780907D01*
X173449D01*
X173219Y781011D01*
X173028Y781269D01*
X172951Y781631D01*
X173066Y781992D01*
X173334Y782251D01*
X173641Y782354D01*
X173948Y782251D01*
X174216Y781992D01*
X174331Y781631D01*
X174254Y781269D01*
X174063Y781011D01*
X173833Y780907D01*
X173449D01*
X173104Y780752D01*
X172874Y780442D01*
X172798Y780081D01*
X172874Y779719D01*
X173066Y779461D01*
X173373Y779306D01*
X173641Y779254D01*
G01X153756Y779457D02*
Y785657D01*
X156956D01*
Y779457D01*
X153756D01*
G01X164957Y784194D02*
Y787294D01*
X165916D01*
X166222Y787139D01*
X166414Y786932D01*
X166491Y786519D01*
X166414Y786106D01*
X166184Y785847D01*
X165916Y785692D01*
X164957D01*
G01X165916D02*
X166491Y784194D01*
G01X168096Y786777D02*
X168326Y787087D01*
X168594Y787242D01*
X168901Y787294D01*
X169284Y787191D01*
X169552Y786932D01*
X169629Y786622D01*
X169591Y786312D01*
X169437Y786054D01*
X168671Y785537D01*
X168326Y785176D01*
X168096Y784659D01*
X168019Y784194D01*
X169629D01*
G01X160044Y782541D02*
X153844D01*
Y785741D01*
X160044D01*
Y782541D01*
G01X168855Y789649D02*
X165755D01*
Y790608D01*
X165910Y790914D01*
X166117Y791106D01*
X166530Y791183D01*
X166943Y791106D01*
X167202Y790876D01*
X167357Y790608D01*
Y789649D01*
G01Y790608D02*
X168855Y791183D01*
G01X168493Y792864D02*
X168752Y793133D01*
X168855Y793439D01*
X168752Y793746D01*
X168442Y794014D01*
X167977Y794206D01*
X167512Y794283D01*
X166943D01*
X166478Y794206D01*
X166065Y794014D01*
X165858Y793784D01*
X165755Y793516D01*
X165858Y793209D01*
X166065Y792979D01*
X166375Y792826D01*
X166788Y792749D01*
X167150Y792826D01*
X167512Y793018D01*
X167718Y793248D01*
X167770Y793516D01*
X167667Y793823D01*
X167408Y794053D01*
X166943Y794283D01*
G01X168855Y797076D02*
X165755D01*
X167977Y795658D01*
Y797574D01*
G01X156962Y788805D02*
Y782605D01*
X153762D01*
Y788805D01*
X156962D01*
G01X167682Y871238D02*
Y874338D01*
X168602D01*
X168909Y874183D01*
X169139Y873821D01*
X169216Y873408D01*
X169139Y872995D01*
X168947Y872685D01*
X168602Y872530D01*
X167682D01*
G01X170706Y871858D02*
X170936Y871496D01*
X171242Y871290D01*
X171587Y871238D01*
X171894Y871290D01*
X172201Y871548D01*
X172392Y871858D01*
X172431Y872168D01*
X172354Y872530D01*
X172086Y872788D01*
X171817Y872891D01*
X171472D01*
G01X171817D02*
X172047Y873046D01*
X172239Y873305D01*
X172316Y873615D01*
X172239Y873925D01*
X172047Y874183D01*
X171702Y874338D01*
X171357Y874286D01*
X171012Y874080D01*
G01X173921Y873821D02*
X174151Y874131D01*
X174419Y874286D01*
X174726Y874338D01*
X175109Y874235D01*
X175377Y873976D01*
X175454Y873666D01*
X175416Y873356D01*
X175262Y873098D01*
X174496Y872581D01*
X174151Y872220D01*
X173921Y871703D01*
X173844Y871238D01*
X175454D01*
G01X166359Y936892D02*
Y939992D01*
X167318D01*
X167624Y939837D01*
X167816Y939630D01*
X167893Y939217D01*
X167816Y938804D01*
X167586Y938545D01*
X167318Y938390D01*
X166359D01*
G01X167318D02*
X167893Y936892D01*
G01X170226D02*
X170494Y936944D01*
X170801Y937099D01*
X170993Y937357D01*
X171069Y937719D01*
X170993Y938080D01*
X170763Y938390D01*
X170418Y938545D01*
X170034D01*
X169804Y938649D01*
X169613Y938907D01*
X169536Y939269D01*
X169651Y939630D01*
X169919Y939889D01*
X170226Y939992D01*
X170533Y939889D01*
X170801Y939630D01*
X170916Y939269D01*
X170839Y938907D01*
X170648Y938649D01*
X170418Y938545D01*
X170034D01*
X169689Y938390D01*
X169459Y938080D01*
X169383Y937719D01*
X169459Y937357D01*
X169651Y937099D01*
X169958Y936944D01*
X170226Y936892D01*
G01X173326D02*
X173594Y936944D01*
X173901Y937099D01*
X174093Y937357D01*
X174169Y937719D01*
X174093Y938080D01*
X173863Y938390D01*
X173518Y938545D01*
X173134D01*
X172904Y938649D01*
X172713Y938907D01*
X172636Y939269D01*
X172751Y939630D01*
X173019Y939889D01*
X173326Y939992D01*
X173633Y939889D01*
X173901Y939630D01*
X174016Y939269D01*
X173939Y938907D01*
X173748Y938649D01*
X173518Y938545D01*
X173134D01*
X172789Y938390D01*
X172559Y938080D01*
X172483Y937719D01*
X172559Y937357D01*
X172751Y937099D01*
X173058Y936944D01*
X173326Y936892D01*
G01X166001Y942671D02*
Y945771D01*
X166960D01*
X167266Y945616D01*
X167458Y945409D01*
X167535Y944996D01*
X167458Y944583D01*
X167228Y944324D01*
X166960Y944169D01*
X166001D01*
G01X166960D02*
X167535Y942671D01*
G01X169868D02*
X170136Y942723D01*
X170443Y942878D01*
X170635Y943136D01*
X170711Y943498D01*
X170635Y943859D01*
X170405Y944169D01*
X170060Y944324D01*
X169676D01*
X169446Y944428D01*
X169255Y944686D01*
X169178Y945048D01*
X169293Y945409D01*
X169561Y945668D01*
X169868Y945771D01*
X170175Y945668D01*
X170443Y945409D01*
X170558Y945048D01*
X170481Y944686D01*
X170290Y944428D01*
X170060Y944324D01*
X169676D01*
X169331Y944169D01*
X169101Y943859D01*
X169025Y943498D01*
X169101Y943136D01*
X169293Y942878D01*
X169600Y942723D01*
X169868Y942671D01*
G01X172316Y943033D02*
X172585Y942774D01*
X172891Y942671D01*
X173198Y942774D01*
X173466Y943084D01*
X173658Y943549D01*
X173735Y944014D01*
Y944583D01*
X173658Y945048D01*
X173466Y945461D01*
X173236Y945668D01*
X172968Y945771D01*
X172661Y945668D01*
X172431Y945461D01*
X172278Y945151D01*
X172201Y944738D01*
X172278Y944376D01*
X172470Y944014D01*
X172700Y943808D01*
X172968Y943756D01*
X173275Y943859D01*
X173505Y944118D01*
X173735Y944583D01*
G01X165988Y961072D02*
Y964172D01*
X166947D01*
X167253Y964017D01*
X167445Y963810D01*
X167522Y963397D01*
X167445Y962984D01*
X167215Y962725D01*
X166947Y962570D01*
X165988D01*
G01X166947D02*
X167522Y961072D01*
G01X169203Y961434D02*
X169472Y961175D01*
X169778Y961072D01*
X170085Y961175D01*
X170353Y961485D01*
X170545Y961950D01*
X170622Y962415D01*
Y962984D01*
X170545Y963449D01*
X170353Y963862D01*
X170123Y964069D01*
X169855Y964172D01*
X169548Y964069D01*
X169318Y963862D01*
X169165Y963552D01*
X169088Y963139D01*
X169165Y962777D01*
X169357Y962415D01*
X169587Y962209D01*
X169855Y962157D01*
X170162Y962260D01*
X170392Y962519D01*
X170622Y962984D01*
G01X172955Y961072D02*
Y964172D01*
X172495Y963552D01*
G01Y961072D02*
X173415D01*
G01X166350Y954839D02*
Y957939D01*
X167309D01*
X167615Y957784D01*
X167807Y957577D01*
X167884Y957164D01*
X167807Y956751D01*
X167577Y956492D01*
X167309Y956337D01*
X166350D01*
G01X167309D02*
X167884Y954839D01*
G01X169565Y955201D02*
X169834Y954942D01*
X170140Y954839D01*
X170447Y954942D01*
X170715Y955252D01*
X170907Y955717D01*
X170984Y956182D01*
Y956751D01*
X170907Y957216D01*
X170715Y957629D01*
X170485Y957836D01*
X170217Y957939D01*
X169910Y957836D01*
X169680Y957629D01*
X169527Y957319D01*
X169450Y956906D01*
X169527Y956544D01*
X169719Y956182D01*
X169949Y955976D01*
X170217Y955924D01*
X170524Y956027D01*
X170754Y956286D01*
X170984Y956751D01*
G01X172589Y957422D02*
X172819Y957732D01*
X173087Y957887D01*
X173394Y957939D01*
X173777Y957836D01*
X174045Y957577D01*
X174122Y957267D01*
X174084Y956957D01*
X173930Y956699D01*
X173164Y956182D01*
X172819Y955821D01*
X172589Y955304D01*
X172512Y954839D01*
X174122D01*
G01X149853Y1025472D02*
X150121Y1025833D01*
X150351Y1026040D01*
X150658Y1026143D01*
X150926Y1026040D01*
X151118Y1025833D01*
X151271Y1025523D01*
X151309Y1025162D01*
X151271Y1024852D01*
X151118Y1024542D01*
X150888Y1024283D01*
X150619Y1024180D01*
X150313Y1024283D01*
X150044Y1024593D01*
X149891Y1025058D01*
X149853Y1025575D01*
X149929Y1026247D01*
X150044Y1026608D01*
X150236Y1026970D01*
X150504Y1027228D01*
X150773Y1027280D01*
X151041Y1027177D01*
X151233Y1026918D01*
G01X154141Y1024180D02*
Y1027280D01*
X152723Y1025058D01*
X154639D01*
G01X149946Y1047207D02*
X150176Y1046845D01*
X150482Y1046639D01*
X150827Y1046587D01*
X151134Y1046639D01*
X151441Y1046897D01*
X151632Y1047207D01*
X151671Y1047517D01*
X151594Y1047879D01*
X151326Y1048137D01*
X151057Y1048240D01*
X150712D01*
G01X151057D02*
X151287Y1048395D01*
X151479Y1048654D01*
X151556Y1048964D01*
X151479Y1049274D01*
X151287Y1049532D01*
X150942Y1049687D01*
X150597Y1049635D01*
X150252Y1049429D01*
G01X153046Y1047207D02*
X153276Y1046845D01*
X153582Y1046639D01*
X153927Y1046587D01*
X154234Y1046639D01*
X154541Y1046897D01*
X154732Y1047207D01*
X154771Y1047517D01*
X154694Y1047879D01*
X154426Y1048137D01*
X154157Y1048240D01*
X153812D01*
G01X154157D02*
X154387Y1048395D01*
X154579Y1048654D01*
X154656Y1048964D01*
X154579Y1049274D01*
X154387Y1049532D01*
X154042Y1049687D01*
X153697Y1049635D01*
X153352Y1049429D01*
G01X162648Y1024545D02*
Y1027645D01*
X163607D01*
X163913Y1027490D01*
X164105Y1027283D01*
X164182Y1026870D01*
X164105Y1026457D01*
X163875Y1026198D01*
X163607Y1026043D01*
X162648D01*
G01X163607D02*
X164182Y1024545D01*
G01X166515D02*
Y1027645D01*
X166055Y1027025D01*
G01Y1024545D02*
X166975D01*
G01X169615Y1027645D02*
X169308Y1027542D01*
X169078Y1027283D01*
X168925Y1026973D01*
X168810Y1026560D01*
X168772Y1026095D01*
X168810Y1025630D01*
X168925Y1025217D01*
X169078Y1024907D01*
X169308Y1024648D01*
X169615Y1024545D01*
X169922Y1024648D01*
X170152Y1024907D01*
X170305Y1025217D01*
X170420Y1025630D01*
X170458Y1026095D01*
X170420Y1026560D01*
X170305Y1026973D01*
X170152Y1027283D01*
X169922Y1027542D01*
X169615Y1027645D01*
G01X171872Y1025165D02*
X172102Y1024803D01*
X172408Y1024597D01*
X172753Y1024545D01*
X173060Y1024597D01*
X173367Y1024855D01*
X173558Y1025165D01*
X173597Y1025475D01*
X173520Y1025837D01*
X173252Y1026095D01*
X172983Y1026198D01*
X172638D01*
G01X172983D02*
X173213Y1026353D01*
X173405Y1026612D01*
X173482Y1026922D01*
X173405Y1027232D01*
X173213Y1027490D01*
X172868Y1027645D01*
X172523Y1027593D01*
X172178Y1027387D01*
G01X163035Y1029441D02*
Y1032541D01*
X163994D01*
X164300Y1032386D01*
X164492Y1032179D01*
X164569Y1031766D01*
X164492Y1031353D01*
X164262Y1031094D01*
X163994Y1030939D01*
X163035D01*
G01X163994D02*
X164569Y1029441D01*
G01X166902D02*
Y1032541D01*
X166442Y1031921D01*
G01Y1029441D02*
X167362D01*
G01X170002Y1032541D02*
X169695Y1032438D01*
X169465Y1032179D01*
X169312Y1031869D01*
X169197Y1031456D01*
X169159Y1030991D01*
X169197Y1030526D01*
X169312Y1030113D01*
X169465Y1029803D01*
X169695Y1029544D01*
X170002Y1029441D01*
X170309Y1029544D01*
X170539Y1029803D01*
X170692Y1030113D01*
X170807Y1030526D01*
X170845Y1030991D01*
X170807Y1031456D01*
X170692Y1031869D01*
X170539Y1032179D01*
X170309Y1032438D01*
X170002Y1032541D01*
G01X173562Y1029441D02*
Y1032541D01*
X172144Y1030319D01*
X174060D01*
G01X168472Y1044649D02*
Y1047749D01*
X169392D01*
X169699Y1047594D01*
X169929Y1047232D01*
X170006Y1046819D01*
X169929Y1046406D01*
X169737Y1046096D01*
X169392Y1045941D01*
X168472D01*
G01X171496Y1045269D02*
X171726Y1044907D01*
X172032Y1044701D01*
X172377Y1044649D01*
X172684Y1044701D01*
X172991Y1044959D01*
X173182Y1045269D01*
X173221Y1045579D01*
X173144Y1045941D01*
X172876Y1046199D01*
X172607Y1046302D01*
X172262D01*
G01X172607D02*
X172837Y1046457D01*
X173029Y1046716D01*
X173106Y1047026D01*
X173029Y1047336D01*
X172837Y1047594D01*
X172492Y1047749D01*
X172147Y1047697D01*
X171802Y1047491D01*
G01X174711Y1047232D02*
X174941Y1047542D01*
X175209Y1047697D01*
X175516Y1047749D01*
X175899Y1047646D01*
X176167Y1047387D01*
X176244Y1047077D01*
X176206Y1046767D01*
X176052Y1046509D01*
X175286Y1045992D01*
X174941Y1045631D01*
X174711Y1045114D01*
X174634Y1044649D01*
X176244D01*
G01X169157Y1111160D02*
X166057D01*
Y1112119D01*
X166212Y1112425D01*
X166419Y1112617D01*
X166832Y1112694D01*
X167245Y1112617D01*
X167504Y1112387D01*
X167659Y1112119D01*
Y1111160D01*
G01Y1112119D02*
X169157Y1112694D01*
G01Y1115027D02*
X166057D01*
X166677Y1114567D01*
G01X169157D02*
Y1115487D01*
G01X167865Y1117399D02*
X167504Y1117667D01*
X167297Y1117897D01*
X167194Y1118204D01*
X167297Y1118472D01*
X167504Y1118664D01*
X167814Y1118817D01*
X168175Y1118855D01*
X168485Y1118817D01*
X168795Y1118664D01*
X169054Y1118434D01*
X169157Y1118165D01*
X169054Y1117859D01*
X168744Y1117590D01*
X168279Y1117437D01*
X167762Y1117399D01*
X167090Y1117475D01*
X166729Y1117590D01*
X166367Y1117782D01*
X166109Y1118050D01*
X166057Y1118319D01*
X166160Y1118587D01*
X166419Y1118779D01*
G01X157717Y1117652D02*
Y1111452D01*
X154517D01*
Y1117652D01*
X157717D01*
G01X164462Y1105229D02*
Y1108329D01*
X165421D01*
X165727Y1108174D01*
X165919Y1107967D01*
X165996Y1107554D01*
X165919Y1107141D01*
X165689Y1106882D01*
X165421Y1106727D01*
X164462D01*
G01X165421D02*
X165996Y1105229D01*
G01X167601Y1107812D02*
X167831Y1108122D01*
X168099Y1108277D01*
X168406Y1108329D01*
X168789Y1108226D01*
X169057Y1107967D01*
X169134Y1107657D01*
X169096Y1107347D01*
X168942Y1107089D01*
X168176Y1106572D01*
X167831Y1106211D01*
X167601Y1105694D01*
X167524Y1105229D01*
X169134D01*
G01X170586Y1105694D02*
X170816Y1105436D01*
X171084Y1105281D01*
X171429Y1105229D01*
X171774Y1105332D01*
X172042Y1105539D01*
X172234Y1105901D01*
X172272Y1106314D01*
X172196Y1106727D01*
X172004Y1106986D01*
X171736Y1107192D01*
X171467Y1107244D01*
X171199Y1107192D01*
X170854Y1106986D01*
X170969Y1108329D01*
X172004D01*
G01X160803Y1105253D02*
X154603D01*
Y1108453D01*
X160803D01*
Y1105253D01*
G01X162470Y1117660D02*
Y1111460D01*
X159270D01*
Y1117660D01*
X162470D01*
G01X163205Y1118928D02*
X160105D01*
Y1119887D01*
X160260Y1120193D01*
X160467Y1120385D01*
X160880Y1120462D01*
X161293Y1120385D01*
X161552Y1120155D01*
X161707Y1119887D01*
Y1118928D01*
G01Y1119887D02*
X163205Y1120462D01*
G01Y1122795D02*
X160105D01*
X160725Y1122335D01*
G01X163205D02*
Y1123255D01*
G01X160622Y1125167D02*
X160312Y1125397D01*
X160157Y1125665D01*
X160105Y1125972D01*
X160208Y1126355D01*
X160467Y1126623D01*
X160777Y1126700D01*
X161087Y1126662D01*
X161345Y1126508D01*
X161862Y1125742D01*
X162223Y1125397D01*
X162740Y1125167D01*
X163205Y1125090D01*
Y1126700D01*
G01X160622Y1128267D02*
X160312Y1128497D01*
X160157Y1128765D01*
X160105Y1129072D01*
X160208Y1129455D01*
X160467Y1129723D01*
X160777Y1129800D01*
X161087Y1129762D01*
X161345Y1129608D01*
X161862Y1128842D01*
X162223Y1128497D01*
X162740Y1128267D01*
X163205Y1128190D01*
Y1129800D01*
G01X161796Y1131030D02*
Y1134130D01*
X162755D01*
X163061Y1133975D01*
X163253Y1133768D01*
X163330Y1133355D01*
X163253Y1132942D01*
X163023Y1132683D01*
X162755Y1132528D01*
X161796D01*
G01X162755D02*
X163330Y1131030D01*
G01X165663D02*
Y1134130D01*
X165203Y1133510D01*
G01Y1131030D02*
X166123D01*
G01X167920Y1131495D02*
X168150Y1131237D01*
X168418Y1131082D01*
X168763Y1131030D01*
X169108Y1131133D01*
X169376Y1131340D01*
X169568Y1131702D01*
X169606Y1132115D01*
X169530Y1132528D01*
X169338Y1132787D01*
X169070Y1132993D01*
X168801Y1133045D01*
X168533Y1132993D01*
X168188Y1132787D01*
X168303Y1134130D01*
X169338D01*
G01X160022Y1130578D02*
X153822D01*
Y1133778D01*
X160022D01*
Y1130578D01*
G01X156662Y1138751D02*
X153562D01*
Y1139710D01*
X153717Y1140016D01*
X153924Y1140208D01*
X154337Y1140285D01*
X154750Y1140208D01*
X155009Y1139978D01*
X155164Y1139710D01*
Y1138751D01*
G01Y1139710D02*
X156662Y1140285D01*
G01Y1142618D02*
X153562D01*
X154182Y1142158D01*
G01X156662D02*
Y1143078D01*
G01X153562Y1145718D02*
X153665Y1145411D01*
X153924Y1145181D01*
X154234Y1145028D01*
X154647Y1144913D01*
X155112Y1144875D01*
X155577Y1144913D01*
X155990Y1145028D01*
X156300Y1145181D01*
X156559Y1145411D01*
X156662Y1145718D01*
X156559Y1146025D01*
X156300Y1146255D01*
X155990Y1146408D01*
X155577Y1146523D01*
X155112Y1146561D01*
X154647Y1146523D01*
X154234Y1146408D01*
X153924Y1146255D01*
X153665Y1146025D01*
X153562Y1145718D01*
G01X155370Y1148090D02*
X155009Y1148358D01*
X154802Y1148588D01*
X154699Y1148895D01*
X154802Y1149163D01*
X155009Y1149355D01*
X155319Y1149508D01*
X155680Y1149546D01*
X155990Y1149508D01*
X156300Y1149355D01*
X156559Y1149125D01*
X156662Y1148856D01*
X156559Y1148550D01*
X156249Y1148281D01*
X155784Y1148128D01*
X155267Y1148090D01*
X154595Y1148166D01*
X154234Y1148281D01*
X153872Y1148473D01*
X153614Y1148741D01*
X153562Y1149010D01*
X153665Y1149278D01*
X153924Y1149470D01*
G01X156864Y1136869D02*
Y1130669D01*
X153664D01*
Y1136869D01*
X156864D01*
G01X153663Y1127520D02*
Y1133720D01*
X156863D01*
Y1127520D01*
X153663D01*
G01X168613Y1215637D02*
X168383Y1215792D01*
X168115Y1215895D01*
X167808D01*
X167463Y1215740D01*
X167195Y1215482D01*
X167003Y1215172D01*
X166850Y1214655D01*
X166812Y1214190D01*
X166888Y1213725D01*
X167003Y1213415D01*
X167233Y1213105D01*
X167502Y1212898D01*
X167770Y1212795D01*
X168038D01*
X168307Y1212898D01*
X168537Y1213053D01*
X168728Y1213260D01*
G01X171637Y1212795D02*
X170103D01*
Y1215895D01*
X171637D01*
G01X171023Y1214397D02*
X170103D01*
G01X173970Y1212795D02*
Y1215895D01*
X173510Y1215275D01*
G01Y1212795D02*
X174430D01*
G01X177530D02*
Y1215895D01*
X176112Y1213673D01*
X178028D01*
G01X168868Y1220297D02*
Y1223397D01*
X169788D01*
X170095Y1223242D01*
X170325Y1222880D01*
X170402Y1222467D01*
X170325Y1222054D01*
X170133Y1221744D01*
X169788Y1221589D01*
X168868D01*
G01X171892Y1220917D02*
X172122Y1220555D01*
X172428Y1220349D01*
X172773Y1220297D01*
X173080Y1220349D01*
X173387Y1220607D01*
X173578Y1220917D01*
X173617Y1221227D01*
X173540Y1221589D01*
X173272Y1221847D01*
X173003Y1221950D01*
X172658D01*
G01X173003D02*
X173233Y1222105D01*
X173425Y1222364D01*
X173502Y1222674D01*
X173425Y1222984D01*
X173233Y1223242D01*
X172888Y1223397D01*
X172543Y1223345D01*
X172198Y1223139D01*
G01X175107Y1222880D02*
X175337Y1223190D01*
X175605Y1223345D01*
X175912Y1223397D01*
X176295Y1223294D01*
X176563Y1223035D01*
X176640Y1222725D01*
X176602Y1222415D01*
X176448Y1222157D01*
X175682Y1221640D01*
X175337Y1221279D01*
X175107Y1220762D01*
X175030Y1220297D01*
X176640D01*
G01X151613Y1323252D02*
X151805Y1322942D01*
X152035Y1322735D01*
X152303Y1322632D01*
X152610Y1322735D01*
X152840Y1322942D01*
X153070Y1323252D01*
X153147Y1323665D01*
Y1325732D01*
G01X155940Y1322632D02*
Y1325732D01*
X154522Y1323510D01*
X156438D01*
G01X150274Y1372812D02*
X150542Y1373173D01*
X150772Y1373380D01*
X151079Y1373483D01*
X151347Y1373380D01*
X151539Y1373173D01*
X151692Y1372863D01*
X151730Y1372502D01*
X151692Y1372192D01*
X151539Y1371882D01*
X151309Y1371623D01*
X151040Y1371520D01*
X150734Y1371623D01*
X150465Y1371933D01*
X150312Y1372398D01*
X150274Y1372915D01*
X150350Y1373587D01*
X150465Y1373948D01*
X150657Y1374310D01*
X150925Y1374568D01*
X151194Y1374620D01*
X151462Y1374517D01*
X151654Y1374258D01*
G01X154562Y1371520D02*
Y1374620D01*
X153144Y1372398D01*
X155060D01*
G01X150343Y1397243D02*
X150573Y1396881D01*
X150879Y1396675D01*
X151224Y1396623D01*
X151531Y1396675D01*
X151838Y1396933D01*
X152029Y1397243D01*
X152068Y1397553D01*
X151991Y1397915D01*
X151723Y1398173D01*
X151454Y1398276D01*
X151109D01*
G01X151454D02*
X151684Y1398431D01*
X151876Y1398690D01*
X151953Y1399000D01*
X151876Y1399310D01*
X151684Y1399568D01*
X151339Y1399723D01*
X150994Y1399671D01*
X150649Y1399465D01*
G01X153443Y1397243D02*
X153673Y1396881D01*
X153979Y1396675D01*
X154324Y1396623D01*
X154631Y1396675D01*
X154938Y1396933D01*
X155129Y1397243D01*
X155168Y1397553D01*
X155091Y1397915D01*
X154823Y1398173D01*
X154554Y1398276D01*
X154209D01*
G01X154554D02*
X154784Y1398431D01*
X154976Y1398690D01*
X155053Y1399000D01*
X154976Y1399310D01*
X154784Y1399568D01*
X154439Y1399723D01*
X154094Y1399671D01*
X153749Y1399465D01*
G01X170053Y1395675D02*
Y1398775D01*
X170973D01*
X171280Y1398620D01*
X171510Y1398258D01*
X171587Y1397845D01*
X171510Y1397432D01*
X171318Y1397122D01*
X170973Y1396967D01*
X170053D01*
G01X173077Y1396295D02*
X173307Y1395933D01*
X173613Y1395727D01*
X173958Y1395675D01*
X174265Y1395727D01*
X174572Y1395985D01*
X174763Y1396295D01*
X174802Y1396605D01*
X174725Y1396967D01*
X174457Y1397225D01*
X174188Y1397328D01*
X173843D01*
G01X174188D02*
X174418Y1397483D01*
X174610Y1397742D01*
X174687Y1398052D01*
X174610Y1398362D01*
X174418Y1398620D01*
X174073Y1398775D01*
X173728Y1398723D01*
X173383Y1398517D01*
G01X176292Y1398258D02*
X176522Y1398568D01*
X176790Y1398723D01*
X177097Y1398775D01*
X177480Y1398672D01*
X177748Y1398413D01*
X177825Y1398103D01*
X177787Y1397793D01*
X177633Y1397535D01*
X176867Y1397018D01*
X176522Y1396657D01*
X176292Y1396140D01*
X176215Y1395675D01*
X177825D01*
G01X166397Y1455646D02*
Y1458746D01*
X167356D01*
X167662Y1458591D01*
X167854Y1458384D01*
X167931Y1457971D01*
X167854Y1457558D01*
X167624Y1457299D01*
X167356Y1457144D01*
X166397D01*
G01X167356D02*
X167931Y1455646D01*
G01X169536Y1458229D02*
X169766Y1458539D01*
X170034Y1458694D01*
X170341Y1458746D01*
X170724Y1458643D01*
X170992Y1458384D01*
X171069Y1458074D01*
X171031Y1457764D01*
X170877Y1457506D01*
X170111Y1456989D01*
X169766Y1456628D01*
X169536Y1456111D01*
X169459Y1455646D01*
X171069D01*
G01X173824D02*
Y1458746D01*
X172406Y1456524D01*
X174322D01*
G01X161777Y1455484D02*
X155577D01*
Y1458684D01*
X161777D01*
Y1455484D01*
G01X165787Y1478921D02*
Y1482021D01*
X166746D01*
X167052Y1481866D01*
X167244Y1481659D01*
X167321Y1481246D01*
X167244Y1480833D01*
X167014Y1480574D01*
X166746Y1480419D01*
X165787D01*
G01X166746D02*
X167321Y1478921D01*
G01X169654D02*
Y1482021D01*
X169194Y1481401D01*
G01Y1478921D02*
X170114D01*
G01X173214D02*
Y1482021D01*
X171796Y1479799D01*
X173712D01*
G01X160501Y1478669D02*
X154301D01*
Y1481869D01*
X160501D01*
Y1478669D01*
G01X165230Y1459883D02*
Y1462983D01*
X166189D01*
X166495Y1462828D01*
X166687Y1462621D01*
X166764Y1462208D01*
X166687Y1461795D01*
X166457Y1461536D01*
X166189Y1461381D01*
X165230D01*
G01X166189D02*
X166764Y1459883D01*
G01X168369Y1462466D02*
X168599Y1462776D01*
X168867Y1462931D01*
X169174Y1462983D01*
X169557Y1462880D01*
X169825Y1462621D01*
X169902Y1462311D01*
X169864Y1462001D01*
X169710Y1461743D01*
X168944Y1461226D01*
X168599Y1460865D01*
X168369Y1460348D01*
X168292Y1459883D01*
X169902D01*
G01X172120D02*
X172197Y1460555D01*
X172312Y1461123D01*
X172465Y1461640D01*
X172657Y1462208D01*
X172964Y1462983D01*
X171430D01*
G01X161030Y1461051D02*
X154830D01*
Y1464251D01*
X161030D01*
Y1461051D01*
G01X165524Y1470028D02*
Y1473128D01*
X166483D01*
X166789Y1472973D01*
X166981Y1472766D01*
X167058Y1472353D01*
X166981Y1471940D01*
X166751Y1471681D01*
X166483Y1471526D01*
X165524D01*
G01X166483D02*
X167058Y1470028D01*
G01X169851D02*
Y1473128D01*
X168433Y1470906D01*
X170349D01*
G01X172951Y1470028D02*
Y1473128D01*
X171533Y1470906D01*
X173449D01*
G01X154123Y1474620D02*
X160323D01*
Y1471420D01*
X154123D01*
Y1474620D01*
G01X157434Y1484949D02*
Y1478749D01*
X154234D01*
Y1484949D01*
X157434D01*
G01X166018Y1474410D02*
Y1477510D01*
X166977D01*
X167283Y1477355D01*
X167475Y1477148D01*
X167552Y1476735D01*
X167475Y1476322D01*
X167245Y1476063D01*
X166977Y1475908D01*
X166018D01*
G01X166977D02*
X167552Y1474410D01*
G01X169885D02*
Y1477510D01*
X169425Y1476890D01*
G01Y1474410D02*
X170345D01*
G01X172257Y1476993D02*
X172487Y1477303D01*
X172755Y1477458D01*
X173062Y1477510D01*
X173445Y1477407D01*
X173713Y1477148D01*
X173790Y1476838D01*
X173752Y1476528D01*
X173598Y1476270D01*
X172832Y1475753D01*
X172487Y1475392D01*
X172257Y1474875D01*
X172180Y1474410D01*
X173790D01*
G01X175357Y1475702D02*
X175625Y1476063D01*
X175855Y1476270D01*
X176162Y1476373D01*
X176430Y1476270D01*
X176622Y1476063D01*
X176775Y1475753D01*
X176813Y1475392D01*
X176775Y1475082D01*
X176622Y1474772D01*
X176392Y1474513D01*
X176123Y1474410D01*
X175817Y1474513D01*
X175548Y1474823D01*
X175395Y1475288D01*
X175357Y1475805D01*
X175433Y1476477D01*
X175548Y1476838D01*
X175740Y1477200D01*
X176008Y1477458D01*
X176277Y1477510D01*
X176545Y1477407D01*
X176737Y1477148D01*
G01X154216Y1475599D02*
Y1481799D01*
X157416D01*
Y1475599D01*
X154216D01*
G01X156852Y1487527D02*
X153752D01*
Y1488486D01*
X153907Y1488792D01*
X154114Y1488984D01*
X154527Y1489061D01*
X154940Y1488984D01*
X155199Y1488754D01*
X155354Y1488486D01*
Y1487527D01*
G01Y1488486D02*
X156852Y1489061D01*
G01Y1491394D02*
X153752D01*
X154372Y1490934D01*
G01X156852D02*
Y1491854D01*
G01X153752Y1494494D02*
X153855Y1494187D01*
X154114Y1493957D01*
X154424Y1493804D01*
X154837Y1493689D01*
X155302Y1493651D01*
X155767Y1493689D01*
X156180Y1493804D01*
X156490Y1493957D01*
X156749Y1494187D01*
X156852Y1494494D01*
X156749Y1494801D01*
X156490Y1495031D01*
X156180Y1495184D01*
X155767Y1495299D01*
X155302Y1495337D01*
X154837Y1495299D01*
X154424Y1495184D01*
X154114Y1495031D01*
X153855Y1494801D01*
X153752Y1494494D01*
G01X154269Y1496866D02*
X153959Y1497096D01*
X153804Y1497364D01*
X153752Y1497671D01*
X153855Y1498054D01*
X154114Y1498322D01*
X154424Y1498399D01*
X154734Y1498361D01*
X154992Y1498207D01*
X155509Y1497441D01*
X155870Y1497096D01*
X156387Y1496866D01*
X156852Y1496789D01*
Y1498399D01*
G01X169525Y1571461D02*
Y1574561D01*
X170445D01*
X170752Y1574406D01*
X170982Y1574044D01*
X171059Y1573631D01*
X170982Y1573218D01*
X170790Y1572908D01*
X170445Y1572753D01*
X169525D01*
G01X172549Y1572081D02*
X172779Y1571719D01*
X173085Y1571513D01*
X173430Y1571461D01*
X173737Y1571513D01*
X174044Y1571771D01*
X174235Y1572081D01*
X174274Y1572391D01*
X174197Y1572753D01*
X173929Y1573011D01*
X173660Y1573114D01*
X173315D01*
G01X173660D02*
X173890Y1573269D01*
X174082Y1573528D01*
X174159Y1573838D01*
X174082Y1574148D01*
X173890Y1574406D01*
X173545Y1574561D01*
X173200Y1574509D01*
X172855Y1574303D01*
G01X175764Y1574044D02*
X175994Y1574354D01*
X176262Y1574509D01*
X176569Y1574561D01*
X176952Y1574458D01*
X177220Y1574199D01*
X177297Y1573889D01*
X177259Y1573579D01*
X177105Y1573321D01*
X176339Y1572804D01*
X175994Y1572443D01*
X175764Y1571926D01*
X175687Y1571461D01*
X177297D01*
G01X150939Y1721106D02*
X151207Y1721467D01*
X151437Y1721674D01*
X151744Y1721777D01*
X152012Y1721674D01*
X152204Y1721467D01*
X152357Y1721157D01*
X152395Y1720796D01*
X152357Y1720486D01*
X152204Y1720176D01*
X151974Y1719917D01*
X151705Y1719814D01*
X151399Y1719917D01*
X151130Y1720227D01*
X150977Y1720692D01*
X150939Y1721209D01*
X151015Y1721881D01*
X151130Y1722242D01*
X151322Y1722604D01*
X151590Y1722862D01*
X151859Y1722914D01*
X152127Y1722811D01*
X152319Y1722552D01*
G01X155227Y1719814D02*
Y1722914D01*
X153809Y1720692D01*
X155725D01*
G01X150942Y1747011D02*
X151172Y1746649D01*
X151478Y1746443D01*
X151823Y1746391D01*
X152130Y1746443D01*
X152437Y1746701D01*
X152628Y1747011D01*
X152667Y1747321D01*
X152590Y1747683D01*
X152322Y1747941D01*
X152053Y1748044D01*
X151708D01*
G01X152053D02*
X152283Y1748199D01*
X152475Y1748458D01*
X152552Y1748768D01*
X152475Y1749078D01*
X152283Y1749336D01*
X151938Y1749491D01*
X151593Y1749439D01*
X151248Y1749233D01*
G01X154042Y1747011D02*
X154272Y1746649D01*
X154578Y1746443D01*
X154923Y1746391D01*
X155230Y1746443D01*
X155537Y1746701D01*
X155728Y1747011D01*
X155767Y1747321D01*
X155690Y1747683D01*
X155422Y1747941D01*
X155153Y1748044D01*
X154808D01*
G01X155153D02*
X155383Y1748199D01*
X155575Y1748458D01*
X155652Y1748768D01*
X155575Y1749078D01*
X155383Y1749336D01*
X155038Y1749491D01*
X154693Y1749439D01*
X154348Y1749233D01*
G01X169418Y1764601D02*
Y1767701D01*
X170338D01*
X170645Y1767546D01*
X170875Y1767184D01*
X170952Y1766771D01*
X170875Y1766358D01*
X170683Y1766048D01*
X170338Y1765893D01*
X169418D01*
G01X172442Y1765221D02*
X172672Y1764859D01*
X172978Y1764653D01*
X173323Y1764601D01*
X173630Y1764653D01*
X173937Y1764911D01*
X174128Y1765221D01*
X174167Y1765531D01*
X174090Y1765893D01*
X173822Y1766151D01*
X173553Y1766254D01*
X173208D01*
G01X173553D02*
X173783Y1766409D01*
X173975Y1766668D01*
X174052Y1766978D01*
X173975Y1767288D01*
X173783Y1767546D01*
X173438Y1767701D01*
X173093Y1767649D01*
X172748Y1767443D01*
G01X175657Y1767184D02*
X175887Y1767494D01*
X176155Y1767649D01*
X176462Y1767701D01*
X176845Y1767598D01*
X177113Y1767339D01*
X177190Y1767029D01*
X177152Y1766719D01*
X176998Y1766461D01*
X176232Y1765944D01*
X175887Y1765583D01*
X175657Y1765066D01*
X175580Y1764601D01*
X177190D01*
G01X161863Y1818441D02*
Y1821541D01*
X162822D01*
X163128Y1821386D01*
X163320Y1821179D01*
X163397Y1820766D01*
X163320Y1820353D01*
X163090Y1820094D01*
X162822Y1819939D01*
X161863D01*
G01X162822D02*
X163397Y1818441D01*
G01X165730D02*
Y1821541D01*
X165270Y1820921D01*
G01Y1818441D02*
X166190D01*
G01X168830D02*
X169098Y1818493D01*
X169405Y1818648D01*
X169597Y1818906D01*
X169673Y1819268D01*
X169597Y1819629D01*
X169367Y1819939D01*
X169022Y1820094D01*
X168638D01*
X168408Y1820198D01*
X168217Y1820456D01*
X168140Y1820818D01*
X168255Y1821179D01*
X168523Y1821438D01*
X168830Y1821541D01*
X169137Y1821438D01*
X169405Y1821179D01*
X169520Y1820818D01*
X169443Y1820456D01*
X169252Y1820198D01*
X169022Y1820094D01*
X168638D01*
X168293Y1819939D01*
X168063Y1819629D01*
X167987Y1819268D01*
X168063Y1818906D01*
X168255Y1818648D01*
X168562Y1818493D01*
X168830Y1818441D01*
G01X153884Y1821960D02*
X160084D01*
Y1818760D01*
X153884D01*
Y1821960D01*
G01X164697Y1805686D02*
Y1808786D01*
X165656D01*
X165962Y1808631D01*
X166154Y1808424D01*
X166231Y1808011D01*
X166154Y1807598D01*
X165924Y1807339D01*
X165656Y1807184D01*
X164697D01*
G01X165656D02*
X166231Y1805686D01*
G01X167836Y1808269D02*
X168066Y1808579D01*
X168334Y1808734D01*
X168641Y1808786D01*
X169024Y1808683D01*
X169292Y1808424D01*
X169369Y1808114D01*
X169331Y1807804D01*
X169177Y1807546D01*
X168411Y1807029D01*
X168066Y1806668D01*
X167836Y1806151D01*
X167759Y1805686D01*
X169369D01*
G01X170936Y1806978D02*
X171204Y1807339D01*
X171434Y1807546D01*
X171741Y1807649D01*
X172009Y1807546D01*
X172201Y1807339D01*
X172354Y1807029D01*
X172392Y1806668D01*
X172354Y1806358D01*
X172201Y1806048D01*
X171971Y1805789D01*
X171702Y1805686D01*
X171396Y1805789D01*
X171127Y1806099D01*
X170974Y1806564D01*
X170936Y1807081D01*
X171012Y1807753D01*
X171127Y1808114D01*
X171319Y1808476D01*
X171587Y1808734D01*
X171856Y1808786D01*
X172124Y1808683D01*
X172316Y1808424D01*
G01X160365Y1806140D02*
X154165D01*
Y1809340D01*
X160365D01*
Y1806140D01*
G01X165178Y1813334D02*
Y1816434D01*
X166137D01*
X166443Y1816279D01*
X166635Y1816072D01*
X166712Y1815659D01*
X166635Y1815246D01*
X166405Y1814987D01*
X166137Y1814832D01*
X165178D01*
G01X166137D02*
X166712Y1813334D01*
G01X168317Y1815917D02*
X168547Y1816227D01*
X168815Y1816382D01*
X169122Y1816434D01*
X169505Y1816331D01*
X169773Y1816072D01*
X169850Y1815762D01*
X169812Y1815452D01*
X169658Y1815194D01*
X168892Y1814677D01*
X168547Y1814316D01*
X168317Y1813799D01*
X168240Y1813334D01*
X169850D01*
G01X171302Y1813954D02*
X171532Y1813592D01*
X171838Y1813386D01*
X172183Y1813334D01*
X172490Y1813386D01*
X172797Y1813644D01*
X172988Y1813954D01*
X173027Y1814264D01*
X172950Y1814626D01*
X172682Y1814884D01*
X172413Y1814987D01*
X172068D01*
G01X172413D02*
X172643Y1815142D01*
X172835Y1815401D01*
X172912Y1815711D01*
X172835Y1816021D01*
X172643Y1816279D01*
X172298Y1816434D01*
X171953Y1816382D01*
X171608Y1816176D01*
G01X160088Y1814031D02*
X153888D01*
Y1817231D01*
X160088D01*
Y1814031D01*
G01X164305Y1827486D02*
Y1830586D01*
X165264D01*
X165570Y1830431D01*
X165762Y1830224D01*
X165839Y1829811D01*
X165762Y1829398D01*
X165532Y1829139D01*
X165264Y1828984D01*
X164305D01*
G01X165264D02*
X165839Y1827486D01*
G01X168172D02*
Y1830586D01*
X167712Y1829966D01*
G01Y1827486D02*
X168632D01*
G01X171195D02*
X171272Y1828158D01*
X171387Y1828726D01*
X171540Y1829243D01*
X171732Y1829811D01*
X172039Y1830586D01*
X170505D01*
G01X160331Y1826625D02*
X154131D01*
Y1829825D01*
X160331D01*
Y1826625D01*
G01X157447Y1834744D02*
X154347D01*
Y1835703D01*
X154502Y1836009D01*
X154709Y1836201D01*
X155122Y1836278D01*
X155535Y1836201D01*
X155794Y1835971D01*
X155949Y1835703D01*
Y1834744D01*
G01Y1835703D02*
X157447Y1836278D01*
G01X157085Y1837959D02*
X157344Y1838228D01*
X157447Y1838534D01*
X157344Y1838841D01*
X157034Y1839109D01*
X156569Y1839301D01*
X156104Y1839378D01*
X155535D01*
X155070Y1839301D01*
X154657Y1839109D01*
X154450Y1838879D01*
X154347Y1838611D01*
X154450Y1838304D01*
X154657Y1838074D01*
X154967Y1837921D01*
X155380Y1837844D01*
X155742Y1837921D01*
X156104Y1838113D01*
X156310Y1838343D01*
X156362Y1838611D01*
X156259Y1838918D01*
X156000Y1839148D01*
X155535Y1839378D01*
G01X157447Y1841711D02*
X157395Y1841979D01*
X157240Y1842286D01*
X156982Y1842478D01*
X156620Y1842554D01*
X156259Y1842478D01*
X155949Y1842248D01*
X155794Y1841903D01*
Y1841519D01*
X155690Y1841289D01*
X155432Y1841098D01*
X155070Y1841021D01*
X154709Y1841136D01*
X154450Y1841404D01*
X154347Y1841711D01*
X154450Y1842018D01*
X154709Y1842286D01*
X155070Y1842401D01*
X155432Y1842324D01*
X155690Y1842133D01*
X155794Y1841903D01*
Y1841519D01*
X155949Y1841174D01*
X156259Y1840944D01*
X156620Y1840868D01*
X156982Y1840944D01*
X157240Y1841136D01*
X157395Y1841443D01*
X157447Y1841711D01*
G01X157170Y1832905D02*
Y1826705D01*
X153970D01*
Y1832905D01*
X157170D01*
G01X163275Y1822631D02*
Y1825731D01*
X164234D01*
X164540Y1825576D01*
X164732Y1825369D01*
X164809Y1824956D01*
X164732Y1824543D01*
X164502Y1824284D01*
X164234Y1824129D01*
X163275D01*
G01X164234D02*
X164809Y1822631D01*
G01X167142D02*
Y1825731D01*
X166682Y1825111D01*
G01Y1822631D02*
X167602D01*
G01X169399Y1823251D02*
X169629Y1822889D01*
X169935Y1822683D01*
X170280Y1822631D01*
X170587Y1822683D01*
X170894Y1822941D01*
X171085Y1823251D01*
X171124Y1823561D01*
X171047Y1823923D01*
X170779Y1824181D01*
X170510Y1824284D01*
X170165D01*
G01X170510D02*
X170740Y1824439D01*
X170932Y1824698D01*
X171009Y1825008D01*
X170932Y1825318D01*
X170740Y1825576D01*
X170395Y1825731D01*
X170050Y1825679D01*
X169705Y1825473D01*
G01X173342Y1825731D02*
X173035Y1825628D01*
X172805Y1825369D01*
X172652Y1825059D01*
X172537Y1824646D01*
X172499Y1824181D01*
X172537Y1823716D01*
X172652Y1823303D01*
X172805Y1822993D01*
X173035Y1822734D01*
X173342Y1822631D01*
X173649Y1822734D01*
X173879Y1822993D01*
X174032Y1823303D01*
X174147Y1823716D01*
X174185Y1824181D01*
X174147Y1824646D01*
X174032Y1825059D01*
X173879Y1825369D01*
X173649Y1825628D01*
X173342Y1825731D01*
G01X153961Y1823562D02*
Y1829762D01*
X157161D01*
Y1823562D01*
X153961D01*
G01X168209Y1920916D02*
Y1924016D01*
X169129D01*
X169436Y1923861D01*
X169666Y1923499D01*
X169743Y1923086D01*
X169666Y1922673D01*
X169474Y1922363D01*
X169129Y1922208D01*
X168209D01*
G01X171233Y1921536D02*
X171463Y1921174D01*
X171769Y1920968D01*
X172114Y1920916D01*
X172421Y1920968D01*
X172728Y1921226D01*
X172919Y1921536D01*
X172958Y1921846D01*
X172881Y1922208D01*
X172613Y1922466D01*
X172344Y1922569D01*
X171999D01*
G01X172344D02*
X172574Y1922724D01*
X172766Y1922983D01*
X172843Y1923293D01*
X172766Y1923603D01*
X172574Y1923861D01*
X172229Y1924016D01*
X171884Y1923964D01*
X171539Y1923758D01*
G01X174448Y1923499D02*
X174678Y1923809D01*
X174946Y1923964D01*
X175253Y1924016D01*
X175636Y1923913D01*
X175904Y1923654D01*
X175981Y1923344D01*
X175943Y1923034D01*
X175789Y1922776D01*
X175023Y1922259D01*
X174678Y1921898D01*
X174448Y1921381D01*
X174371Y1920916D01*
X175981D01*
G01X154718Y2032814D02*
X155028Y2033006D01*
X155235Y2033236D01*
X155338Y2033504D01*
X155235Y2033811D01*
X155028Y2034041D01*
X154718Y2034271D01*
X154305Y2034348D01*
X152238D01*
G01X154046Y2035953D02*
X153685Y2036221D01*
X153478Y2036451D01*
X153375Y2036758D01*
X153478Y2037026D01*
X153685Y2037218D01*
X153995Y2037371D01*
X154356Y2037409D01*
X154666Y2037371D01*
X154976Y2037218D01*
X155235Y2036988D01*
X155338Y2036719D01*
X155235Y2036413D01*
X154925Y2036144D01*
X154460Y2035991D01*
X153943Y2035953D01*
X153271Y2036029D01*
X152910Y2036144D01*
X152548Y2036336D01*
X152290Y2036604D01*
X152238Y2036873D01*
X152341Y2037141D01*
X152600Y2037333D01*
G01X149964Y2069341D02*
X150232Y2069702D01*
X150462Y2069909D01*
X150769Y2070012D01*
X151037Y2069909D01*
X151229Y2069702D01*
X151382Y2069392D01*
X151420Y2069031D01*
X151382Y2068721D01*
X151229Y2068411D01*
X150999Y2068152D01*
X150730Y2068049D01*
X150424Y2068152D01*
X150155Y2068462D01*
X150002Y2068927D01*
X149964Y2069444D01*
X150040Y2070116D01*
X150155Y2070477D01*
X150347Y2070839D01*
X150615Y2071097D01*
X150884Y2071149D01*
X151152Y2071046D01*
X151344Y2070787D01*
G01X154252Y2068049D02*
Y2071149D01*
X152834Y2068927D01*
X154750D01*
G01X172654Y55758D02*
Y58858D01*
X173574D01*
X173881Y58703D01*
X174111Y58341D01*
X174188Y57928D01*
X174111Y57515D01*
X173919Y57205D01*
X173574Y57050D01*
X172654D01*
G01X176521Y55758D02*
Y58858D01*
X176061Y58238D01*
G01Y55758D02*
X176981D01*
G01X213452Y73105D02*
G03I-16800J0D01*
G01X193986Y131602D02*
X193756Y131757D01*
X193488Y131860D01*
X193181D01*
X192836Y131705D01*
X192568Y131447D01*
X192376Y131137D01*
X192223Y130620D01*
X192185Y130155D01*
X192261Y129690D01*
X192376Y129380D01*
X192606Y129070D01*
X192875Y128863D01*
X193143Y128760D01*
X193411D01*
X193680Y128863D01*
X193910Y129018D01*
X194101Y129225D01*
G01X197010Y128760D02*
X195476D01*
Y131860D01*
X197010D01*
G01X196396Y130362D02*
X195476D01*
G01X198615Y131343D02*
X198845Y131653D01*
X199113Y131808D01*
X199420Y131860D01*
X199803Y131757D01*
X200071Y131498D01*
X200148Y131188D01*
X200110Y130878D01*
X199956Y130620D01*
X199190Y130103D01*
X198845Y129742D01*
X198615Y129225D01*
X198538Y128760D01*
X200148D01*
G01X213979Y152050D02*
G03I-16800J0D01*
G01X177034Y170205D02*
Y173305D01*
X177954D01*
X178261Y173150D01*
X178491Y172788D01*
X178568Y172375D01*
X178491Y171962D01*
X178299Y171652D01*
X177954Y171497D01*
X177034D01*
G01X180134Y170205D02*
Y173305D01*
X181093D01*
X181399Y173150D01*
X181591Y172943D01*
X181668Y172530D01*
X181591Y172117D01*
X181361Y171858D01*
X181093Y171703D01*
X180134D01*
G01X181093D02*
X181668Y170205D01*
G01X184768D02*
X183234D01*
Y173305D01*
X184768D01*
G01X184154Y171807D02*
X183234D01*
G01X186296Y170618D02*
X186603Y170360D01*
X186948Y170205D01*
X187254D01*
X187561Y170360D01*
X187791Y170618D01*
X187906Y170980D01*
X187829Y171342D01*
X187638Y171652D01*
X187293Y171858D01*
X186833Y171962D01*
X186564Y172168D01*
X186449Y172530D01*
X186526Y172892D01*
X186718Y173150D01*
X186986Y173305D01*
X187254D01*
X187523Y173202D01*
X187753Y172943D01*
G01X189396Y170618D02*
X189703Y170360D01*
X190048Y170205D01*
X190354D01*
X190661Y170360D01*
X190891Y170618D01*
X191006Y170980D01*
X190929Y171342D01*
X190738Y171652D01*
X190393Y171858D01*
X189933Y171962D01*
X189664Y172168D01*
X189549Y172530D01*
X189626Y172892D01*
X189818Y173150D01*
X190086Y173305D01*
X190354D01*
X190623Y173202D01*
X190853Y172943D01*
G01X192803Y171238D02*
X193799D01*
G01X195673Y170205D02*
Y173305D01*
X197129D01*
G01X196593Y171807D02*
X195673D01*
G01X199041Y173305D02*
X199961D01*
G01X199501D02*
Y170205D01*
G01X199041D02*
X199961D01*
G01X202601Y173305D02*
Y170205D01*
G01X201719Y173305D02*
X203483D01*
G01X214047Y247568D02*
G03I-16800J0D01*
G01X171864Y232720D02*
Y235820D01*
X172784D01*
X173091Y235665D01*
X173321Y235303D01*
X173398Y234890D01*
X173321Y234477D01*
X173129Y234167D01*
X172784Y234012D01*
X171864D01*
G01X175731Y232720D02*
Y235820D01*
X175271Y235200D01*
G01Y232720D02*
X176191D01*
G01X192577Y312666D02*
X192347Y312821D01*
X192079Y312924D01*
X191772D01*
X191427Y312769D01*
X191159Y312511D01*
X190967Y312201D01*
X190814Y311684D01*
X190776Y311219D01*
X190852Y310754D01*
X190967Y310444D01*
X191197Y310134D01*
X191466Y309927D01*
X191734Y309824D01*
X192002D01*
X192271Y309927D01*
X192501Y310082D01*
X192692Y310289D01*
G01X195601Y309824D02*
X194067D01*
Y312924D01*
X195601D01*
G01X194987Y311426D02*
X194067D01*
G01X198394Y309824D02*
Y312924D01*
X196976Y310702D01*
X198892D01*
G01X214507Y331786D02*
G03I-16800J0D01*
G01X213451Y421732D02*
G03I-16800J0D01*
G01X179759Y407054D02*
Y410154D01*
X180679D01*
X180986Y409999D01*
X181216Y409637D01*
X181293Y409224D01*
X181216Y408811D01*
X181024Y408501D01*
X180679Y408346D01*
X179759D01*
G01X183626Y407054D02*
Y410154D01*
X183166Y409534D01*
G01Y407054D02*
X184086D01*
G01X214243Y506517D02*
G03I-16800J0D01*
G01X216578Y598130D02*
G03I-16800J0D01*
G01X214506Y681645D02*
G03I-16800J0D01*
G01X171108Y737301D02*
Y740401D01*
X172028D01*
X172335Y740246D01*
X172565Y739884D01*
X172642Y739471D01*
X172565Y739058D01*
X172373Y738748D01*
X172028Y738593D01*
X171108D01*
G01X174975Y737301D02*
Y740401D01*
X174515Y739781D01*
G01Y737301D02*
X175435D01*
G01X215536Y774526D02*
G03I-16800J0D01*
G01X215296Y856244D02*
G03I-16800J0D01*
G01X220001Y947202D02*
G03I-16800J0D01*
G01X185898Y936379D02*
X179698D01*
Y939579D01*
X185898D01*
Y936379D01*
G01X185809Y941979D02*
X179609D01*
Y945179D01*
X185809D01*
Y941979D01*
G01X170811Y931235D02*
Y934335D01*
X171731D01*
X172038Y934180D01*
X172268Y933818D01*
X172345Y933405D01*
X172268Y932992D01*
X172076Y932682D01*
X171731Y932527D01*
X170811D01*
G01X174678Y931235D02*
Y934335D01*
X174218Y933715D01*
G01Y931235D02*
X175138D01*
G01X185721Y961071D02*
X179521D01*
Y964271D01*
X185721D01*
Y961071D01*
G01X185810Y955471D02*
X179610D01*
Y958671D01*
X185810D01*
Y955471D01*
G01X187100Y974346D02*
Y977446D01*
X188059D01*
X188365Y977291D01*
X188557Y977084D01*
X188634Y976671D01*
X188557Y976258D01*
X188327Y975999D01*
X188059Y975844D01*
X187100D01*
G01X188059D02*
X188634Y974346D01*
G01X190315Y974708D02*
X190584Y974449D01*
X190890Y974346D01*
X191197Y974449D01*
X191465Y974759D01*
X191657Y975224D01*
X191734Y975689D01*
Y976258D01*
X191657Y976723D01*
X191465Y977136D01*
X191235Y977343D01*
X190967Y977446D01*
X190660Y977343D01*
X190430Y977136D01*
X190277Y976826D01*
X190200Y976413D01*
X190277Y976051D01*
X190469Y975689D01*
X190699Y975483D01*
X190967Y975431D01*
X191274Y975534D01*
X191504Y975793D01*
X191734Y976258D01*
G01X193224Y974811D02*
X193454Y974553D01*
X193722Y974398D01*
X194067Y974346D01*
X194412Y974449D01*
X194680Y974656D01*
X194872Y975018D01*
X194910Y975431D01*
X194834Y975844D01*
X194642Y976103D01*
X194374Y976309D01*
X194105Y976361D01*
X193837Y976309D01*
X193492Y976103D01*
X193607Y977446D01*
X194642D01*
G01X187206Y970014D02*
Y973114D01*
X188165D01*
X188471Y972959D01*
X188663Y972752D01*
X188740Y972339D01*
X188663Y971926D01*
X188433Y971667D01*
X188165Y971512D01*
X187206D01*
G01X188165D02*
X188740Y970014D01*
G01X190421Y970376D02*
X190690Y970117D01*
X190996Y970014D01*
X191303Y970117D01*
X191571Y970427D01*
X191763Y970892D01*
X191840Y971357D01*
Y971926D01*
X191763Y972391D01*
X191571Y972804D01*
X191341Y973011D01*
X191073Y973114D01*
X190766Y973011D01*
X190536Y972804D01*
X190383Y972494D01*
X190306Y972081D01*
X190383Y971719D01*
X190575Y971357D01*
X190805Y971151D01*
X191073Y971099D01*
X191380Y971202D01*
X191610Y971461D01*
X191840Y971926D01*
G01X193445Y971306D02*
X193713Y971667D01*
X193943Y971874D01*
X194250Y971977D01*
X194518Y971874D01*
X194710Y971667D01*
X194863Y971357D01*
X194901Y970996D01*
X194863Y970686D01*
X194710Y970376D01*
X194480Y970117D01*
X194211Y970014D01*
X193905Y970117D01*
X193636Y970427D01*
X193483Y970892D01*
X193445Y971409D01*
X193521Y972081D01*
X193636Y972442D01*
X193828Y972804D01*
X194096Y973062D01*
X194365Y973114D01*
X194633Y973011D01*
X194825Y972752D01*
G01X186064Y971954D02*
X179864D01*
Y975154D01*
X186064D01*
Y971954D01*
G01X173483Y984476D02*
Y987576D01*
X174442D01*
X174748Y987421D01*
X174940Y987214D01*
X175017Y986801D01*
X174940Y986388D01*
X174710Y986129D01*
X174442Y985974D01*
X173483D01*
G01X174442D02*
X175017Y984476D01*
G01X177350D02*
Y987576D01*
X176890Y986956D01*
G01Y984476D02*
X177810D01*
G01X180450Y987576D02*
X180143Y987473D01*
X179913Y987214D01*
X179760Y986904D01*
X179645Y986491D01*
X179607Y986026D01*
X179645Y985561D01*
X179760Y985148D01*
X179913Y984838D01*
X180143Y984579D01*
X180450Y984476D01*
X180757Y984579D01*
X180987Y984838D01*
X181140Y985148D01*
X181255Y985561D01*
X181293Y986026D01*
X181255Y986491D01*
X181140Y986904D01*
X180987Y987214D01*
X180757Y987473D01*
X180450Y987576D01*
G01X183550D02*
X183243Y987473D01*
X183013Y987214D01*
X182860Y986904D01*
X182745Y986491D01*
X182707Y986026D01*
X182745Y985561D01*
X182860Y985148D01*
X183013Y984838D01*
X183243Y984579D01*
X183550Y984476D01*
X183857Y984579D01*
X184087Y984838D01*
X184240Y985148D01*
X184355Y985561D01*
X184393Y986026D01*
X184355Y986491D01*
X184240Y986904D01*
X184087Y987214D01*
X183857Y987473D01*
X183550Y987576D01*
G01X185922Y989358D02*
X179722D01*
Y992558D01*
X185922D01*
Y989358D01*
G01X186157Y977554D02*
X179957D01*
Y980754D01*
X186157D01*
Y977554D01*
G01X185878Y994958D02*
X179678D01*
Y998158D01*
X185878D01*
Y994958D01*
G01X219206Y1032544D02*
G03I-16800J0D01*
G01X186989Y1012316D02*
Y1015416D01*
X187948D01*
X188254Y1015261D01*
X188446Y1015054D01*
X188523Y1014641D01*
X188446Y1014228D01*
X188216Y1013969D01*
X187948Y1013814D01*
X186989D01*
G01X187948D02*
X188523Y1012316D01*
G01X190856D02*
Y1015416D01*
X190396Y1014796D01*
G01Y1012316D02*
X191316D01*
G01X193956Y1015416D02*
X193649Y1015313D01*
X193419Y1015054D01*
X193266Y1014744D01*
X193151Y1014331D01*
X193113Y1013866D01*
X193151Y1013401D01*
X193266Y1012988D01*
X193419Y1012678D01*
X193649Y1012419D01*
X193956Y1012316D01*
X194263Y1012419D01*
X194493Y1012678D01*
X194646Y1012988D01*
X194761Y1013401D01*
X194799Y1013866D01*
X194761Y1014331D01*
X194646Y1014744D01*
X194493Y1015054D01*
X194263Y1015313D01*
X193956Y1015416D01*
G01X196979Y1012316D02*
X197056Y1012988D01*
X197171Y1013556D01*
X197324Y1014073D01*
X197516Y1014641D01*
X197823Y1015416D01*
X196289D01*
G01X185643Y1013713D02*
X179443D01*
Y1016913D01*
X185643D01*
Y1013713D01*
G01X186991Y1007344D02*
Y1010444D01*
X187950D01*
X188256Y1010289D01*
X188448Y1010082D01*
X188525Y1009669D01*
X188448Y1009256D01*
X188218Y1008997D01*
X187950Y1008842D01*
X186991D01*
G01X187950D02*
X188525Y1007344D01*
G01X190858D02*
Y1010444D01*
X190398Y1009824D01*
G01Y1007344D02*
X191318D01*
G01X193958Y1010444D02*
X193651Y1010341D01*
X193421Y1010082D01*
X193268Y1009772D01*
X193153Y1009359D01*
X193115Y1008894D01*
X193153Y1008429D01*
X193268Y1008016D01*
X193421Y1007706D01*
X193651Y1007447D01*
X193958Y1007344D01*
X194265Y1007447D01*
X194495Y1007706D01*
X194648Y1008016D01*
X194763Y1008429D01*
X194801Y1008894D01*
X194763Y1009359D01*
X194648Y1009772D01*
X194495Y1010082D01*
X194265Y1010341D01*
X193958Y1010444D01*
G01X197058Y1007344D02*
X197326Y1007396D01*
X197633Y1007551D01*
X197825Y1007809D01*
X197901Y1008171D01*
X197825Y1008532D01*
X197595Y1008842D01*
X197250Y1008997D01*
X196866D01*
X196636Y1009101D01*
X196445Y1009359D01*
X196368Y1009721D01*
X196483Y1010082D01*
X196751Y1010341D01*
X197058Y1010444D01*
X197365Y1010341D01*
X197633Y1010082D01*
X197748Y1009721D01*
X197671Y1009359D01*
X197480Y1009101D01*
X197250Y1008997D01*
X196866D01*
X196521Y1008842D01*
X196291Y1008532D01*
X196215Y1008171D01*
X196291Y1007809D01*
X196483Y1007551D01*
X196790Y1007396D01*
X197058Y1007344D01*
G01X185640Y1008113D02*
X179440D01*
Y1011313D01*
X185640D01*
Y1008113D01*
G01X174404Y999738D02*
Y1002838D01*
X175363D01*
X175669Y1002683D01*
X175861Y1002476D01*
X175938Y1002063D01*
X175861Y1001650D01*
X175631Y1001391D01*
X175363Y1001236D01*
X174404D01*
G01X175363D02*
X175938Y999738D01*
G01X177619Y1000100D02*
X177888Y999841D01*
X178194Y999738D01*
X178501Y999841D01*
X178769Y1000151D01*
X178961Y1000616D01*
X179038Y1001081D01*
Y1001650D01*
X178961Y1002115D01*
X178769Y1002528D01*
X178539Y1002735D01*
X178271Y1002838D01*
X177964Y1002735D01*
X177734Y1002528D01*
X177581Y1002218D01*
X177504Y1001805D01*
X177581Y1001443D01*
X177773Y1001081D01*
X178003Y1000875D01*
X178271Y1000823D01*
X178578Y1000926D01*
X178808Y1001185D01*
X179038Y1001650D01*
G01X180719Y1000100D02*
X180988Y999841D01*
X181294Y999738D01*
X181601Y999841D01*
X181869Y1000151D01*
X182061Y1000616D01*
X182138Y1001081D01*
Y1001650D01*
X182061Y1002115D01*
X181869Y1002528D01*
X181639Y1002735D01*
X181371Y1002838D01*
X181064Y1002735D01*
X180834Y1002528D01*
X180681Y1002218D01*
X180604Y1001805D01*
X180681Y1001443D01*
X180873Y1001081D01*
X181103Y1000875D01*
X181371Y1000823D01*
X181678Y1000926D01*
X181908Y1001185D01*
X182138Y1001650D01*
G01X183854Y1023422D02*
X177654D01*
Y1026622D01*
X183854D01*
Y1023422D01*
G01X183852Y1029022D02*
X177652D01*
Y1032222D01*
X183852D01*
Y1029022D01*
G01X214940Y1122856D02*
G03I-16800J0D01*
G01X173510Y1111215D02*
X170410D01*
Y1112174D01*
X170565Y1112480D01*
X170772Y1112672D01*
X171185Y1112749D01*
X171598Y1112672D01*
X171857Y1112442D01*
X172012Y1112174D01*
Y1111215D01*
G01Y1112174D02*
X173510Y1112749D01*
G01X170927Y1114354D02*
X170617Y1114584D01*
X170462Y1114852D01*
X170410Y1115159D01*
X170513Y1115542D01*
X170772Y1115810D01*
X171082Y1115887D01*
X171392Y1115849D01*
X171650Y1115695D01*
X172167Y1114929D01*
X172528Y1114584D01*
X173045Y1114354D01*
X173510Y1114277D01*
Y1115887D01*
G01Y1118182D02*
X170410D01*
X171030Y1117722D01*
G01X173510D02*
Y1118642D01*
G01X177390Y1105435D02*
Y1108535D01*
X178310D01*
X178617Y1108380D01*
X178847Y1108018D01*
X178924Y1107605D01*
X178847Y1107192D01*
X178655Y1106882D01*
X178310Y1106727D01*
X177390D01*
G01X181257Y1105435D02*
Y1108535D01*
X180797Y1107915D01*
G01Y1105435D02*
X181717D01*
G01X215032Y1206233D02*
G03I-16800J0D01*
G01X215536Y1299104D02*
G03I-16800J0D01*
G01X170944Y1280820D02*
Y1283920D01*
X171864D01*
X172171Y1283765D01*
X172401Y1283403D01*
X172478Y1282990D01*
X172401Y1282577D01*
X172209Y1282267D01*
X171864Y1282112D01*
X170944D01*
G01X174811Y1280820D02*
Y1283920D01*
X174351Y1283300D01*
G01Y1280820D02*
X175271D01*
G01X194186Y1323741D02*
X193956Y1323896D01*
X193688Y1323999D01*
X193381D01*
X193036Y1323844D01*
X192768Y1323586D01*
X192576Y1323276D01*
X192423Y1322759D01*
X192385Y1322294D01*
X192461Y1321829D01*
X192576Y1321519D01*
X192806Y1321209D01*
X193075Y1321002D01*
X193343Y1320899D01*
X193611D01*
X193880Y1321002D01*
X194110Y1321157D01*
X194301Y1321364D01*
G01X197210Y1320899D02*
X195676D01*
Y1323999D01*
X197210D01*
G01X196596Y1322501D02*
X195676D01*
G01X199543Y1320899D02*
Y1323999D01*
X199083Y1323379D01*
G01Y1320899D02*
X200003D01*
G01X201800Y1321364D02*
X202030Y1321106D01*
X202298Y1320951D01*
X202643Y1320899D01*
X202988Y1321002D01*
X203256Y1321209D01*
X203448Y1321571D01*
X203486Y1321984D01*
X203410Y1322397D01*
X203218Y1322656D01*
X202950Y1322862D01*
X202681Y1322914D01*
X202413Y1322862D01*
X202068Y1322656D01*
X202183Y1323999D01*
X203218D01*
G01X214242Y1380966D02*
G03I-16800J0D01*
G01X178050Y1455218D02*
Y1458318D01*
X178970D01*
X179277Y1458163D01*
X179507Y1457801D01*
X179584Y1457388D01*
X179507Y1456975D01*
X179315Y1456665D01*
X178970Y1456510D01*
X178050D01*
G01X181917Y1455218D02*
Y1458318D01*
X181457Y1457698D01*
G01Y1455218D02*
X182377D01*
G01X213153Y1474162D02*
G03I-16800J0D01*
G01X214769Y1557277D02*
G03I-16800J0D01*
G01X215833Y1648177D02*
G03I-16800J0D01*
G01X172917Y1630669D02*
Y1633769D01*
X173837D01*
X174144Y1633614D01*
X174374Y1633252D01*
X174451Y1632839D01*
X174374Y1632426D01*
X174182Y1632116D01*
X173837Y1631961D01*
X172917D01*
G01X176784Y1630669D02*
Y1633769D01*
X176324Y1633149D01*
G01Y1630669D02*
X177244D01*
G01X175599Y1663960D02*
X175369Y1664115D01*
X175101Y1664218D01*
X174794D01*
X174449Y1664063D01*
X174181Y1663805D01*
X173989Y1663495D01*
X173836Y1662978D01*
X173798Y1662513D01*
X173874Y1662048D01*
X173989Y1661738D01*
X174219Y1661428D01*
X174488Y1661221D01*
X174756Y1661118D01*
X175024D01*
X175293Y1661221D01*
X175523Y1661376D01*
X175714Y1661583D01*
G01X178623Y1661118D02*
X177089D01*
Y1664218D01*
X178623D01*
G01X178009Y1662720D02*
X177089D01*
G01X180956Y1661118D02*
Y1664218D01*
X180496Y1663598D01*
G01Y1661118D02*
X181416D01*
G01X183404Y1661480D02*
X183673Y1661221D01*
X183979Y1661118D01*
X184286Y1661221D01*
X184554Y1661531D01*
X184746Y1661996D01*
X184823Y1662461D01*
Y1663030D01*
X184746Y1663495D01*
X184554Y1663908D01*
X184324Y1664115D01*
X184056Y1664218D01*
X183749Y1664115D01*
X183519Y1663908D01*
X183366Y1663598D01*
X183289Y1663185D01*
X183366Y1662823D01*
X183558Y1662461D01*
X183788Y1662255D01*
X184056Y1662203D01*
X184363Y1662306D01*
X184593Y1662565D01*
X184823Y1663030D01*
G01X215297Y1731351D02*
G03I-16800J0D01*
G01X171338Y1787109D02*
Y1790209D01*
X172258D01*
X172565Y1790054D01*
X172795Y1789692D01*
X172872Y1789279D01*
X172795Y1788866D01*
X172603Y1788556D01*
X172258Y1788401D01*
X171338D01*
G01X175205Y1787109D02*
Y1790209D01*
X174745Y1789589D01*
G01Y1787109D02*
X175665D01*
G01X215220Y1823227D02*
G03I-16800J0D01*
G01X213979Y1900420D02*
G03I-16800J0D01*
G01X186931Y1919337D02*
Y1922437D01*
X187851D01*
X188158Y1922282D01*
X188388Y1921920D01*
X188465Y1921507D01*
X188388Y1921094D01*
X188196Y1920784D01*
X187851Y1920629D01*
X186931D01*
G01X190031Y1919337D02*
Y1922437D01*
X190990D01*
X191296Y1922282D01*
X191488Y1922075D01*
X191565Y1921662D01*
X191488Y1921249D01*
X191258Y1920990D01*
X190990Y1920835D01*
X190031D01*
G01X190990D02*
X191565Y1919337D01*
G01X194665D02*
X193131D01*
Y1922437D01*
X194665D01*
G01X194051Y1920939D02*
X193131D01*
G01X196193Y1919750D02*
X196500Y1919492D01*
X196845Y1919337D01*
X197151D01*
X197458Y1919492D01*
X197688Y1919750D01*
X197803Y1920112D01*
X197726Y1920474D01*
X197535Y1920784D01*
X197190Y1920990D01*
X196730Y1921094D01*
X196461Y1921300D01*
X196346Y1921662D01*
X196423Y1922024D01*
X196615Y1922282D01*
X196883Y1922437D01*
X197151D01*
X197420Y1922334D01*
X197650Y1922075D01*
G01X199293Y1919750D02*
X199600Y1919492D01*
X199945Y1919337D01*
X200251D01*
X200558Y1919492D01*
X200788Y1919750D01*
X200903Y1920112D01*
X200826Y1920474D01*
X200635Y1920784D01*
X200290Y1920990D01*
X199830Y1921094D01*
X199561Y1921300D01*
X199446Y1921662D01*
X199523Y1922024D01*
X199715Y1922282D01*
X199983Y1922437D01*
X200251D01*
X200520Y1922334D01*
X200750Y1922075D01*
G01X202700Y1920370D02*
X203696D01*
G01X205570Y1919337D02*
Y1922437D01*
X207026D01*
G01X206490Y1920939D02*
X205570D01*
G01X208938Y1922437D02*
X209858D01*
G01X209398D02*
Y1919337D01*
G01X208938D02*
X209858D01*
G01X212498Y1922437D02*
Y1919337D01*
G01X211616Y1922437D02*
X213380D01*
G01X215815Y1998730D02*
G03I-16800J0D01*
G01X170811Y1980123D02*
Y1983223D01*
X171731D01*
X172038Y1983068D01*
X172268Y1982706D01*
X172345Y1982293D01*
X172268Y1981880D01*
X172076Y1981570D01*
X171731Y1981415D01*
X170811D01*
G01X174678Y1980123D02*
Y1983223D01*
X174218Y1982603D01*
G01Y1980123D02*
X175138D01*
G01X190223Y2021792D02*
X189993Y2021947D01*
X189725Y2022050D01*
X189418D01*
X189073Y2021895D01*
X188805Y2021637D01*
X188613Y2021327D01*
X188460Y2020810D01*
X188422Y2020345D01*
X188498Y2019880D01*
X188613Y2019570D01*
X188843Y2019260D01*
X189112Y2019053D01*
X189380Y2018950D01*
X189648D01*
X189917Y2019053D01*
X190147Y2019208D01*
X190338Y2019415D01*
G01X193247Y2018950D02*
X191713D01*
Y2022050D01*
X193247D01*
G01X192633Y2020552D02*
X191713D01*
G01X194852Y2021533D02*
X195082Y2021843D01*
X195350Y2021998D01*
X195657Y2022050D01*
X196040Y2021947D01*
X196308Y2021688D01*
X196385Y2021378D01*
X196347Y2021068D01*
X196193Y2020810D01*
X195427Y2020293D01*
X195082Y2019932D01*
X194852Y2019415D01*
X194775Y2018950D01*
X196385D01*
G01X197837Y2019570D02*
X198067Y2019208D01*
X198373Y2019002D01*
X198718Y2018950D01*
X199025Y2019002D01*
X199332Y2019260D01*
X199523Y2019570D01*
X199562Y2019880D01*
X199485Y2020242D01*
X199217Y2020500D01*
X198948Y2020603D01*
X198603D01*
G01X198948D02*
X199178Y2020758D01*
X199370Y2021017D01*
X199447Y2021327D01*
X199370Y2021637D01*
X199178Y2021895D01*
X198833Y2022050D01*
X198488Y2021998D01*
X198143Y2021792D01*
G01X215220Y2043388D02*
G03I-16800J0D01*
G01X213400Y-103934D02*
X214200Y-104600D01*
X215100Y-105000D01*
X215900D01*
X216700Y-104600D01*
X217300Y-103934D01*
X217600Y-103000D01*
X217400Y-102067D01*
X216900Y-101267D01*
X216000Y-100733D01*
X214800Y-100467D01*
X214100Y-99933D01*
X213800Y-99000D01*
X214000Y-98067D01*
X214500Y-97400D01*
X215200Y-97000D01*
X215900D01*
X216600Y-97267D01*
X217200Y-97933D01*
G01X222300Y-97000D02*
X224700D01*
G01X223500D02*
Y-105000D01*
G01X222300D02*
X224700D01*
G01X229500Y-97000D02*
Y-105000D01*
X233500D01*
G01X237300D02*
Y-97000D01*
G01X241100D02*
X237300Y-101934D01*
G01X241700Y-105000D02*
X239000Y-99667D01*
G01X246200Y-102333D02*
X248800D01*
G01X255500Y-97000D02*
Y-105000D01*
G01X253200Y-97000D02*
X257800D01*
G01X263500Y-105000D02*
X262700Y-104867D01*
X262000Y-104333D01*
X261400Y-103533D01*
X261000Y-102600D01*
X260800Y-101533D01*
Y-100467D01*
X261000Y-99400D01*
X261400Y-98467D01*
X262000Y-97667D01*
X262700Y-97133D01*
X263500Y-97000D01*
X264300Y-97133D01*
X265000Y-97667D01*
X265600Y-98467D01*
X266000Y-99400D01*
X266200Y-100467D01*
Y-101533D01*
X266000Y-102600D01*
X265600Y-103533D01*
X265000Y-104333D01*
X264300Y-104867D01*
X263500Y-105000D01*
G01X269500D02*
Y-97000D01*
X271900D01*
X272700Y-97400D01*
X273300Y-98333D01*
X273500Y-99400D01*
X273300Y-100467D01*
X272800Y-101267D01*
X271900Y-101667D01*
X269500D01*
G01X202000Y-72000D02*
Y-80000D01*
X206000D01*
G01X213800D02*
Y-74667D01*
G01Y-75600D02*
X213400Y-75067D01*
X212800Y-74800D01*
X212100Y-74667D01*
X211400Y-74933D01*
X210800Y-75467D01*
X210400Y-76267D01*
X210200Y-77333D01*
X210400Y-78400D01*
X210800Y-79200D01*
X211400Y-79733D01*
X212100Y-80000D01*
X212800Y-79867D01*
X213400Y-79467D01*
X213800Y-78934D01*
G01X217900Y-82400D02*
X218500Y-82667D01*
X219300Y-82400D01*
X219800Y-81867D01*
X220200Y-81200D01*
X220800Y-79067D01*
X222100Y-74667D01*
G01X218900D02*
X220800Y-79067D01*
G01X226500Y-76400D02*
X229700D01*
X229400Y-75467D01*
X228900Y-74933D01*
X228200Y-74667D01*
X227500Y-74800D01*
X226900Y-75200D01*
X226500Y-76133D01*
X226300Y-76934D01*
Y-77733D01*
X226500Y-78533D01*
X227000Y-79333D01*
X227600Y-79867D01*
X228300Y-80000D01*
X229000Y-79733D01*
X229700Y-78934D01*
G01X234600Y-80000D02*
Y-74667D01*
G01Y-75733D02*
X235100Y-75200D01*
X235600Y-74800D01*
X236300Y-74667D01*
X236800Y-74800D01*
X237400Y-75200D01*
G01X208051Y56284D02*
Y59384D01*
X208971D01*
X209278Y59229D01*
X209508Y58867D01*
X209585Y58454D01*
X209508Y58041D01*
X209316Y57731D01*
X208971Y57576D01*
X208051D01*
G01X211151Y56284D02*
Y59384D01*
X212110D01*
X212416Y59229D01*
X212608Y59022D01*
X212685Y58609D01*
X212608Y58196D01*
X212378Y57937D01*
X212110Y57782D01*
X211151D01*
G01X212110D02*
X212685Y56284D01*
G01X215785D02*
X214251D01*
Y59384D01*
X215785D01*
G01X215171Y57886D02*
X214251D01*
G01X217313Y56697D02*
X217620Y56439D01*
X217965Y56284D01*
X218271D01*
X218578Y56439D01*
X218808Y56697D01*
X218923Y57059D01*
X218846Y57421D01*
X218655Y57731D01*
X218310Y57937D01*
X217850Y58041D01*
X217581Y58247D01*
X217466Y58609D01*
X217543Y58971D01*
X217735Y59229D01*
X218003Y59384D01*
X218271D01*
X218540Y59281D01*
X218770Y59022D01*
G01X220413Y56697D02*
X220720Y56439D01*
X221065Y56284D01*
X221371D01*
X221678Y56439D01*
X221908Y56697D01*
X222023Y57059D01*
X221946Y57421D01*
X221755Y57731D01*
X221410Y57937D01*
X220950Y58041D01*
X220681Y58247D01*
X220566Y58609D01*
X220643Y58971D01*
X220835Y59229D01*
X221103Y59384D01*
X221371D01*
X221640Y59281D01*
X221870Y59022D01*
G01X223820Y57317D02*
X224816D01*
G01X226690Y56284D02*
Y59384D01*
X228146D01*
G01X227610Y57886D02*
X226690D01*
G01X230058Y59384D02*
X230978D01*
G01X230518D02*
Y56284D01*
G01X230058D02*
X230978D01*
G01X233618Y59384D02*
Y56284D01*
G01X232736Y59384D02*
X234500D01*
G01X216209Y63985D02*
X215289D01*
G01X215787Y63313D02*
Y64656D01*
G01X216551Y69400D02*
X216321Y69555D01*
X216053Y69658D01*
X215746D01*
X215401Y69503D01*
X215133Y69245D01*
X214941Y68935D01*
X214788Y68418D01*
X214750Y67953D01*
X214826Y67488D01*
X214941Y67178D01*
X215171Y66868D01*
X215440Y66661D01*
X215708Y66558D01*
X215976D01*
X216245Y66661D01*
X216475Y66816D01*
X216666Y67023D01*
G01X219575Y66558D02*
X218041D01*
Y69658D01*
X219575D01*
G01X218961Y68160D02*
X218041D01*
G01X221908Y66558D02*
Y69658D01*
X221448Y69038D01*
G01Y66558D02*
X222368D01*
G01X196652Y56305D02*
Y89905D01*
G01X197179Y135250D02*
Y168850D01*
G01X210755Y165053D02*
X209835D01*
G01X210333Y164381D02*
Y165724D01*
G01X219158Y247485D02*
X218238D01*
G01X218736Y246813D02*
Y248156D01*
G01X197247Y230768D02*
Y264368D01*
G01X215089Y258696D02*
X214859Y258851D01*
X214591Y258954D01*
X214284D01*
X213939Y258799D01*
X213671Y258541D01*
X213479Y258231D01*
X213326Y257714D01*
X213288Y257249D01*
X213364Y256784D01*
X213479Y256474D01*
X213709Y256164D01*
X213978Y255957D01*
X214246Y255854D01*
X214514D01*
X214783Y255957D01*
X215013Y256112D01*
X215204Y256319D01*
G01X218113Y255854D02*
X216579D01*
Y258954D01*
X218113D01*
G01X217499Y257456D02*
X216579D01*
G01X219603Y256474D02*
X219833Y256112D01*
X220139Y255906D01*
X220484Y255854D01*
X220791Y255906D01*
X221098Y256164D01*
X221289Y256474D01*
X221328Y256784D01*
X221251Y257146D01*
X220983Y257404D01*
X220714Y257507D01*
X220369D01*
G01X220714D02*
X220944Y257662D01*
X221136Y257921D01*
X221213Y258231D01*
X221136Y258541D01*
X220944Y258799D01*
X220599Y258954D01*
X220254Y258902D01*
X219909Y258696D01*
G01X211170Y317869D02*
X210250D01*
G01X210748Y317197D02*
Y318540D01*
G01X197707Y314986D02*
Y348586D01*
G01X212194Y339952D02*
Y343052D01*
X213114D01*
X213421Y342897D01*
X213651Y342535D01*
X213728Y342122D01*
X213651Y341709D01*
X213459Y341399D01*
X213114Y341244D01*
X212194D01*
G01X215294Y339952D02*
Y343052D01*
X216253D01*
X216559Y342897D01*
X216751Y342690D01*
X216828Y342277D01*
X216751Y341864D01*
X216521Y341605D01*
X216253Y341450D01*
X215294D01*
G01X216253D02*
X216828Y339952D01*
G01X219928D02*
X218394D01*
Y343052D01*
X219928D01*
G01X219314Y341554D02*
X218394D01*
G01X221456Y340365D02*
X221763Y340107D01*
X222108Y339952D01*
X222414D01*
X222721Y340107D01*
X222951Y340365D01*
X223066Y340727D01*
X222989Y341089D01*
X222798Y341399D01*
X222453Y341605D01*
X221993Y341709D01*
X221724Y341915D01*
X221609Y342277D01*
X221686Y342639D01*
X221878Y342897D01*
X222146Y343052D01*
X222414D01*
X222683Y342949D01*
X222913Y342690D01*
G01X224556Y340365D02*
X224863Y340107D01*
X225208Y339952D01*
X225514D01*
X225821Y340107D01*
X226051Y340365D01*
X226166Y340727D01*
X226089Y341089D01*
X225898Y341399D01*
X225553Y341605D01*
X225093Y341709D01*
X224824Y341915D01*
X224709Y342277D01*
X224786Y342639D01*
X224978Y342897D01*
X225246Y343052D01*
X225514D01*
X225783Y342949D01*
X226013Y342690D01*
G01X227963Y340985D02*
X228959D01*
G01X230833Y339952D02*
Y343052D01*
X232289D01*
G01X231753Y341554D02*
X230833D01*
G01X234201Y343052D02*
X235121D01*
G01X234661D02*
Y339952D01*
G01X234201D02*
X235121D01*
G01X237761Y343052D02*
Y339952D01*
G01X236879Y343052D02*
X238643D01*
G01X215741Y416498D02*
X214821D01*
G01X215319Y415826D02*
Y417169D01*
G01X196651Y404932D02*
Y438532D01*
G01X219176Y425834D02*
X218946Y425989D01*
X218678Y426092D01*
X218371D01*
X218026Y425937D01*
X217758Y425679D01*
X217566Y425369D01*
X217413Y424852D01*
X217375Y424387D01*
X217451Y423922D01*
X217566Y423612D01*
X217796Y423302D01*
X218065Y423095D01*
X218333Y422992D01*
X218601D01*
X218870Y423095D01*
X219100Y423250D01*
X219291Y423457D01*
G01X222200Y422992D02*
X220666D01*
Y426092D01*
X222200D01*
G01X221586Y424594D02*
X220666D01*
G01X223690Y423457D02*
X223920Y423199D01*
X224188Y423044D01*
X224533Y422992D01*
X224878Y423095D01*
X225146Y423302D01*
X225338Y423664D01*
X225376Y424077D01*
X225300Y424490D01*
X225108Y424749D01*
X224840Y424955D01*
X224571Y425007D01*
X224303Y424955D01*
X223958Y424749D01*
X224073Y426092D01*
X225108D01*
G01X196310Y486226D02*
X196080Y486381D01*
X195812Y486484D01*
X195505D01*
X195160Y486329D01*
X194892Y486071D01*
X194700Y485761D01*
X194547Y485244D01*
X194509Y484779D01*
X194585Y484314D01*
X194700Y484004D01*
X194930Y483694D01*
X195199Y483487D01*
X195467Y483384D01*
X195735D01*
X196004Y483487D01*
X196234Y483642D01*
X196425Y483849D01*
G01X199334Y483384D02*
X197800D01*
Y486484D01*
X199334D01*
G01X198720Y484986D02*
X197800D01*
G01X200939Y484676D02*
X201207Y485037D01*
X201437Y485244D01*
X201744Y485347D01*
X202012Y485244D01*
X202204Y485037D01*
X202357Y484727D01*
X202395Y484366D01*
X202357Y484056D01*
X202204Y483746D01*
X201974Y483487D01*
X201705Y483384D01*
X201399Y483487D01*
X201130Y483797D01*
X200977Y484262D01*
X200939Y484779D01*
X201015Y485451D01*
X201130Y485812D01*
X201322Y486174D01*
X201590Y486432D01*
X201859Y486484D01*
X202127Y486381D01*
X202319Y486122D01*
G01X197443Y489717D02*
Y523317D01*
G01X215298Y499323D02*
X214378D01*
G01X214876Y498651D02*
Y499994D01*
G01X208357Y520860D02*
Y523960D01*
X209277D01*
X209584Y523805D01*
X209814Y523443D01*
X209891Y523030D01*
X209814Y522617D01*
X209622Y522307D01*
X209277Y522152D01*
X208357D01*
G01X211457Y520860D02*
Y523960D01*
X212416D01*
X212722Y523805D01*
X212914Y523598D01*
X212991Y523185D01*
X212914Y522772D01*
X212684Y522513D01*
X212416Y522358D01*
X211457D01*
G01X212416D02*
X212991Y520860D01*
G01X216091D02*
X214557D01*
Y523960D01*
X216091D01*
G01X215477Y522462D02*
X214557D01*
G01X217619Y521273D02*
X217926Y521015D01*
X218271Y520860D01*
X218577D01*
X218884Y521015D01*
X219114Y521273D01*
X219229Y521635D01*
X219152Y521997D01*
X218961Y522307D01*
X218616Y522513D01*
X218156Y522617D01*
X217887Y522823D01*
X217772Y523185D01*
X217849Y523547D01*
X218041Y523805D01*
X218309Y523960D01*
X218577D01*
X218846Y523857D01*
X219076Y523598D01*
G01X220719Y521273D02*
X221026Y521015D01*
X221371Y520860D01*
X221677D01*
X221984Y521015D01*
X222214Y521273D01*
X222329Y521635D01*
X222252Y521997D01*
X222061Y522307D01*
X221716Y522513D01*
X221256Y522617D01*
X220987Y522823D01*
X220872Y523185D01*
X220949Y523547D01*
X221141Y523805D01*
X221409Y523960D01*
X221677D01*
X221946Y523857D01*
X222176Y523598D01*
G01X224126Y521893D02*
X225122D01*
G01X226996Y520860D02*
Y523960D01*
X228452D01*
G01X227916Y522462D02*
X226996D01*
G01X230364Y523960D02*
X231284D01*
G01X230824D02*
Y520860D01*
G01X230364D02*
X231284D01*
G01X233924Y523960D02*
Y520860D01*
G01X233042Y523960D02*
X234806D01*
G01X218722Y587274D02*
X217802D01*
G01X218300Y586602D02*
Y587945D01*
G01X199778Y581330D02*
Y614930D01*
G01X218549Y593477D02*
X218319Y593632D01*
X218051Y593735D01*
X217744D01*
X217399Y593580D01*
X217131Y593322D01*
X216939Y593012D01*
X216786Y592495D01*
X216748Y592030D01*
X216824Y591565D01*
X216939Y591255D01*
X217169Y590945D01*
X217438Y590738D01*
X217706Y590635D01*
X217974D01*
X218243Y590738D01*
X218473Y590893D01*
X218664Y591100D01*
G01X221573Y590635D02*
X220039D01*
Y593735D01*
X221573D01*
G01X220959Y592237D02*
X220039D01*
G01X223906Y590635D02*
X224174Y590687D01*
X224481Y590842D01*
X224673Y591100D01*
X224749Y591462D01*
X224673Y591823D01*
X224443Y592133D01*
X224098Y592288D01*
X223714D01*
X223484Y592392D01*
X223293Y592650D01*
X223216Y593012D01*
X223331Y593373D01*
X223599Y593632D01*
X223906Y593735D01*
X224213Y593632D01*
X224481Y593373D01*
X224596Y593012D01*
X224519Y592650D01*
X224328Y592392D01*
X224098Y592288D01*
X223714D01*
X223369Y592133D01*
X223139Y591823D01*
X223063Y591462D01*
X223139Y591100D01*
X223331Y590842D01*
X223638Y590687D01*
X223906Y590635D01*
G01X199429Y660336D02*
X199199Y660491D01*
X198931Y660594D01*
X198624D01*
X198279Y660439D01*
X198011Y660181D01*
X197819Y659871D01*
X197666Y659354D01*
X197628Y658889D01*
X197704Y658424D01*
X197819Y658114D01*
X198049Y657804D01*
X198318Y657597D01*
X198586Y657494D01*
X198854D01*
X199123Y657597D01*
X199353Y657752D01*
X199544Y657959D01*
G01X202453Y657494D02*
X200919D01*
Y660594D01*
X202453D01*
G01X201839Y659096D02*
X200919D01*
G01X204134Y657856D02*
X204403Y657597D01*
X204709Y657494D01*
X205016Y657597D01*
X205284Y657907D01*
X205476Y658372D01*
X205553Y658837D01*
Y659406D01*
X205476Y659871D01*
X205284Y660284D01*
X205054Y660491D01*
X204786Y660594D01*
X204479Y660491D01*
X204249Y660284D01*
X204096Y659974D01*
X204019Y659561D01*
X204096Y659199D01*
X204288Y658837D01*
X204518Y658631D01*
X204786Y658579D01*
X205093Y658682D01*
X205323Y658941D01*
X205553Y659406D01*
G01X197706Y664845D02*
Y698445D01*
G01X216298Y688702D02*
X215378D01*
G01X215876Y688030D02*
Y689373D01*
G01X198736Y757726D02*
Y791326D01*
G01X198496Y839444D02*
Y873044D01*
G01X219908Y859782D02*
X219678Y859937D01*
X219410Y860040D01*
X219103D01*
X218758Y859885D01*
X218490Y859627D01*
X218298Y859317D01*
X218145Y858800D01*
X218107Y858335D01*
X218183Y857870D01*
X218298Y857560D01*
X218528Y857250D01*
X218797Y857043D01*
X219065Y856940D01*
X219333D01*
X219602Y857043D01*
X219832Y857198D01*
X220023Y857405D01*
G01X222932Y856940D02*
X221398D01*
Y860040D01*
X222932D01*
G01X222318Y858542D02*
X221398D01*
G01X225265Y856940D02*
Y860040D01*
X224805Y859420D01*
G01Y856940D02*
X225725D01*
G01X228365D02*
Y860040D01*
X227905Y859420D01*
G01Y856940D02*
X228825D01*
G01X203201Y930402D02*
Y964002D01*
G01X202406Y1015744D02*
Y1049344D01*
G01X217305Y1049211D02*
X217075Y1049366D01*
X216807Y1049469D01*
X216500D01*
X216155Y1049314D01*
X215887Y1049056D01*
X215695Y1048746D01*
X215542Y1048229D01*
X215504Y1047764D01*
X215580Y1047299D01*
X215695Y1046989D01*
X215925Y1046679D01*
X216194Y1046472D01*
X216462Y1046369D01*
X216730D01*
X216999Y1046472D01*
X217229Y1046627D01*
X217420Y1046834D01*
G01X220329Y1046369D02*
X218795D01*
Y1049469D01*
X220329D01*
G01X219715Y1047971D02*
X218795D01*
G01X222585Y1046369D02*
X222662Y1047041D01*
X222777Y1047609D01*
X222930Y1048126D01*
X223122Y1048694D01*
X223429Y1049469D01*
X221895D01*
G01X198140Y1106056D02*
Y1139656D01*
G01X219712Y1123823D02*
X218792D01*
G01X219290Y1123151D02*
Y1124494D01*
G01X218510Y1131676D02*
X218280Y1131831D01*
X218012Y1131934D01*
X217705D01*
X217360Y1131779D01*
X217092Y1131521D01*
X216900Y1131211D01*
X216747Y1130694D01*
X216709Y1130229D01*
X216785Y1129764D01*
X216900Y1129454D01*
X217130Y1129144D01*
X217399Y1128937D01*
X217667Y1128834D01*
X217935D01*
X218204Y1128937D01*
X218434Y1129092D01*
X218625Y1129299D01*
G01X221534Y1128834D02*
X220000D01*
Y1131934D01*
X221534D01*
G01X220920Y1130436D02*
X220000D01*
G01X223867Y1128834D02*
Y1131934D01*
X223407Y1131314D01*
G01Y1128834D02*
X224327D01*
G01X226124Y1129454D02*
X226354Y1129092D01*
X226660Y1128886D01*
X227005Y1128834D01*
X227312Y1128886D01*
X227619Y1129144D01*
X227810Y1129454D01*
X227849Y1129764D01*
X227772Y1130126D01*
X227504Y1130384D01*
X227235Y1130487D01*
X226890D01*
G01X227235D02*
X227465Y1130642D01*
X227657Y1130901D01*
X227734Y1131211D01*
X227657Y1131521D01*
X227465Y1131779D01*
X227120Y1131934D01*
X226775Y1131882D01*
X226430Y1131676D01*
G01X198232Y1189433D02*
Y1223033D01*
G01X212589Y1220560D02*
Y1223660D01*
X213509D01*
X213816Y1223505D01*
X214046Y1223143D01*
X214123Y1222730D01*
X214046Y1222317D01*
X213854Y1222007D01*
X213509Y1221852D01*
X212589D01*
G01X215689Y1220560D02*
Y1223660D01*
X216648D01*
X216954Y1223505D01*
X217146Y1223298D01*
X217223Y1222885D01*
X217146Y1222472D01*
X216916Y1222213D01*
X216648Y1222058D01*
X215689D01*
G01X216648D02*
X217223Y1220560D01*
G01X220323D02*
X218789D01*
Y1223660D01*
X220323D01*
G01X219709Y1222162D02*
X218789D01*
G01X221851Y1220973D02*
X222158Y1220715D01*
X222503Y1220560D01*
X222809D01*
X223116Y1220715D01*
X223346Y1220973D01*
X223461Y1221335D01*
X223384Y1221697D01*
X223193Y1222007D01*
X222848Y1222213D01*
X222388Y1222317D01*
X222119Y1222523D01*
X222004Y1222885D01*
X222081Y1223247D01*
X222273Y1223505D01*
X222541Y1223660D01*
X222809D01*
X223078Y1223557D01*
X223308Y1223298D01*
G01X224951Y1220973D02*
X225258Y1220715D01*
X225603Y1220560D01*
X225909D01*
X226216Y1220715D01*
X226446Y1220973D01*
X226561Y1221335D01*
X226484Y1221697D01*
X226293Y1222007D01*
X225948Y1222213D01*
X225488Y1222317D01*
X225219Y1222523D01*
X225104Y1222885D01*
X225181Y1223247D01*
X225373Y1223505D01*
X225641Y1223660D01*
X225909D01*
X226178Y1223557D01*
X226408Y1223298D01*
G01X228358Y1221593D02*
X229354D01*
G01X231228Y1220560D02*
Y1223660D01*
X232684D01*
G01X232148Y1222162D02*
X231228D01*
G01X234596Y1223660D02*
X235516D01*
G01X235056D02*
Y1220560D01*
G01X234596D02*
X235516D01*
G01X238156Y1223660D02*
Y1220560D01*
G01X237274Y1223660D02*
X239038D01*
G01X198736Y1282304D02*
Y1315904D01*
G01X218011Y1298047D02*
X217091D01*
G01X217589Y1297375D02*
Y1298718D01*
G01X216434Y1379646D02*
X215514D01*
G01X216012Y1378974D02*
Y1380317D01*
G01X197442Y1364166D02*
Y1397766D01*
G01X217974Y1390224D02*
X217744Y1390379D01*
X217476Y1390482D01*
X217169D01*
X216824Y1390327D01*
X216556Y1390069D01*
X216364Y1389759D01*
X216211Y1389242D01*
X216173Y1388777D01*
X216249Y1388312D01*
X216364Y1388002D01*
X216594Y1387692D01*
X216863Y1387485D01*
X217131Y1387382D01*
X217399D01*
X217668Y1387485D01*
X217898Y1387640D01*
X218089Y1387847D01*
G01X220998Y1387382D02*
X219464D01*
Y1390482D01*
X220998D01*
G01X220384Y1388984D02*
X219464D01*
G01X223331Y1387382D02*
Y1390482D01*
X222871Y1389862D01*
G01Y1387382D02*
X223791D01*
G01X225703Y1388674D02*
X225971Y1389035D01*
X226201Y1389242D01*
X226508Y1389345D01*
X226776Y1389242D01*
X226968Y1389035D01*
X227121Y1388725D01*
X227159Y1388364D01*
X227121Y1388054D01*
X226968Y1387744D01*
X226738Y1387485D01*
X226469Y1387382D01*
X226163Y1387485D01*
X225894Y1387795D01*
X225741Y1388260D01*
X225703Y1388777D01*
X225779Y1389449D01*
X225894Y1389810D01*
X226086Y1390172D01*
X226354Y1390430D01*
X226623Y1390482D01*
X226891Y1390379D01*
X227083Y1390120D01*
G01X215088Y1480502D02*
X214168D01*
G01X214666Y1479830D02*
Y1481173D01*
G01X219167Y1471353D02*
X218937Y1471508D01*
X218669Y1471611D01*
X218362D01*
X218017Y1471456D01*
X217749Y1471198D01*
X217557Y1470888D01*
X217404Y1470371D01*
X217366Y1469906D01*
X217442Y1469441D01*
X217557Y1469131D01*
X217787Y1468821D01*
X218056Y1468614D01*
X218324Y1468511D01*
X218592D01*
X218861Y1468614D01*
X219091Y1468769D01*
X219282Y1468976D01*
G01X222191Y1468511D02*
X220657D01*
Y1471611D01*
X222191D01*
G01X221577Y1470113D02*
X220657D01*
G01X224524Y1468511D02*
Y1471611D01*
X224064Y1470991D01*
G01Y1468511D02*
X224984D01*
G01X227547D02*
X227624Y1469183D01*
X227739Y1469751D01*
X227892Y1470268D01*
X228084Y1470836D01*
X228391Y1471611D01*
X226857D01*
G01X196353Y1457362D02*
Y1490962D01*
G01X216667Y1551238D02*
X215747D01*
G01X216245Y1550566D02*
Y1551909D01*
G01X215057Y1548008D02*
X214827Y1548163D01*
X214559Y1548266D01*
X214252D01*
X213907Y1548111D01*
X213639Y1547853D01*
X213447Y1547543D01*
X213294Y1547026D01*
X213256Y1546561D01*
X213332Y1546096D01*
X213447Y1545786D01*
X213677Y1545476D01*
X213946Y1545269D01*
X214214Y1545166D01*
X214482D01*
X214751Y1545269D01*
X214981Y1545424D01*
X215172Y1545631D01*
G01X218081Y1545166D02*
X216547D01*
Y1548266D01*
X218081D01*
G01X217467Y1546768D02*
X216547D01*
G01X220414Y1545166D02*
Y1548266D01*
X219954Y1547646D01*
G01Y1545166D02*
X220874D01*
G01X223514D02*
X223782Y1545218D01*
X224089Y1545373D01*
X224281Y1545631D01*
X224357Y1545993D01*
X224281Y1546354D01*
X224051Y1546664D01*
X223706Y1546819D01*
X223322D01*
X223092Y1546923D01*
X222901Y1547181D01*
X222824Y1547543D01*
X222939Y1547904D01*
X223207Y1548163D01*
X223514Y1548266D01*
X223821Y1548163D01*
X224089Y1547904D01*
X224204Y1547543D01*
X224127Y1547181D01*
X223936Y1546923D01*
X223706Y1546819D01*
X223322D01*
X222977Y1546664D01*
X222747Y1546354D01*
X222671Y1545993D01*
X222747Y1545631D01*
X222939Y1545373D01*
X223246Y1545218D01*
X223514Y1545166D01*
G01X197969Y1540477D02*
Y1574077D01*
G01X199033Y1631377D02*
Y1664977D01*
G01X218396Y1655303D02*
X217476D01*
G01X217974Y1654631D02*
Y1655974D01*
G01X198497Y1714551D02*
Y1748151D01*
G01X219550Y1743754D02*
X219320Y1743909D01*
X219052Y1744012D01*
X218745D01*
X218400Y1743857D01*
X218132Y1743599D01*
X217940Y1743289D01*
X217787Y1742772D01*
X217749Y1742307D01*
X217825Y1741842D01*
X217940Y1741532D01*
X218170Y1741222D01*
X218439Y1741015D01*
X218707Y1740912D01*
X218975D01*
X219244Y1741015D01*
X219474Y1741170D01*
X219665Y1741377D01*
G01X222574Y1740912D02*
X221040D01*
Y1744012D01*
X222574D01*
G01X221960Y1742514D02*
X221040D01*
G01X224179Y1743495D02*
X224409Y1743805D01*
X224677Y1743960D01*
X224984Y1744012D01*
X225367Y1743909D01*
X225635Y1743650D01*
X225712Y1743340D01*
X225674Y1743030D01*
X225520Y1742772D01*
X224754Y1742255D01*
X224409Y1741894D01*
X224179Y1741377D01*
X224102Y1740912D01*
X225712D01*
G01X228007Y1744012D02*
X227700Y1743909D01*
X227470Y1743650D01*
X227317Y1743340D01*
X227202Y1742927D01*
X227164Y1742462D01*
X227202Y1741997D01*
X227317Y1741584D01*
X227470Y1741274D01*
X227700Y1741015D01*
X228007Y1740912D01*
X228314Y1741015D01*
X228544Y1741274D01*
X228697Y1741584D01*
X228812Y1741997D01*
X228850Y1742462D01*
X228812Y1742927D01*
X228697Y1743340D01*
X228544Y1743650D01*
X228314Y1743909D01*
X228007Y1744012D01*
G01X198420Y1806427D02*
Y1840027D01*
G01X219805Y1833155D02*
X219575Y1833310D01*
X219307Y1833413D01*
X219000D01*
X218655Y1833258D01*
X218387Y1833000D01*
X218195Y1832690D01*
X218042Y1832173D01*
X218004Y1831708D01*
X218080Y1831243D01*
X218195Y1830933D01*
X218425Y1830623D01*
X218694Y1830416D01*
X218962Y1830313D01*
X219230D01*
X219499Y1830416D01*
X219729Y1830571D01*
X219920Y1830778D01*
G01X222829Y1830313D02*
X221295D01*
Y1833413D01*
X222829D01*
G01X222215Y1831915D02*
X221295D01*
G01X224434Y1832896D02*
X224664Y1833206D01*
X224932Y1833361D01*
X225239Y1833413D01*
X225622Y1833310D01*
X225890Y1833051D01*
X225967Y1832741D01*
X225929Y1832431D01*
X225775Y1832173D01*
X225009Y1831656D01*
X224664Y1831295D01*
X224434Y1830778D01*
X224357Y1830313D01*
X225967D01*
G01X227534Y1832896D02*
X227764Y1833206D01*
X228032Y1833361D01*
X228339Y1833413D01*
X228722Y1833310D01*
X228990Y1833051D01*
X229067Y1832741D01*
X229029Y1832431D01*
X228875Y1832173D01*
X228109Y1831656D01*
X227764Y1831295D01*
X227534Y1830778D01*
X227457Y1830313D01*
X229067D01*
G01X197179Y1883620D02*
Y1917220D01*
G01X217110Y1903282D02*
X216190D01*
G01X216688Y1902610D02*
Y1903953D01*
G01X216184Y1911346D02*
X215954Y1911501D01*
X215686Y1911604D01*
X215379D01*
X215034Y1911449D01*
X214766Y1911191D01*
X214574Y1910881D01*
X214421Y1910364D01*
X214383Y1909899D01*
X214459Y1909434D01*
X214574Y1909124D01*
X214804Y1908814D01*
X215073Y1908607D01*
X215341Y1908504D01*
X215609D01*
X215878Y1908607D01*
X216108Y1908762D01*
X216299Y1908969D01*
G01X219208Y1908504D02*
X217674D01*
Y1911604D01*
X219208D01*
G01X218594Y1910106D02*
X217674D01*
G01X220813Y1911087D02*
X221043Y1911397D01*
X221311Y1911552D01*
X221618Y1911604D01*
X222001Y1911501D01*
X222269Y1911242D01*
X222346Y1910932D01*
X222308Y1910622D01*
X222154Y1910364D01*
X221388Y1909847D01*
X221043Y1909486D01*
X220813Y1908969D01*
X220736Y1908504D01*
X222346D01*
G01X224641D02*
Y1911604D01*
X224181Y1910984D01*
G01Y1908504D02*
X225101D01*
G01X199015Y1981930D02*
Y2015530D01*
G01X198420Y2026588D02*
Y2060188D01*
G01X197454Y2067283D02*
X197224Y2067438D01*
X196956Y2067541D01*
X196649D01*
X196304Y2067386D01*
X196036Y2067128D01*
X195844Y2066818D01*
X195691Y2066301D01*
X195653Y2065836D01*
X195729Y2065371D01*
X195844Y2065061D01*
X196074Y2064751D01*
X196343Y2064544D01*
X196611Y2064441D01*
X196879D01*
X197148Y2064544D01*
X197378Y2064699D01*
X197569Y2064906D01*
G01X200478Y2064441D02*
X198944D01*
Y2067541D01*
X200478D01*
G01X199864Y2066043D02*
X198944D01*
G01X202083Y2067024D02*
X202313Y2067334D01*
X202581Y2067489D01*
X202888Y2067541D01*
X203271Y2067438D01*
X203539Y2067179D01*
X203616Y2066869D01*
X203578Y2066559D01*
X203424Y2066301D01*
X202658Y2065784D01*
X202313Y2065423D01*
X202083Y2064906D01*
X202006Y2064441D01*
X203616D01*
G01X206371D02*
Y2067541D01*
X204953Y2065319D01*
X206869D01*
G01X223400Y-128934D02*
X224200Y-129600D01*
X225100Y-130000D01*
X225900D01*
X226700Y-129600D01*
X227300Y-128934D01*
X227600Y-128000D01*
X227400Y-127067D01*
X226900Y-126267D01*
X226000Y-125733D01*
X224800Y-125467D01*
X224100Y-124933D01*
X223800Y-124000D01*
X224000Y-123067D01*
X224500Y-122400D01*
X225200Y-122000D01*
X225900D01*
X226600Y-122267D01*
X227200Y-122933D01*
G01X235300Y-130000D02*
Y-124667D01*
G01Y-125600D02*
X234900Y-125067D01*
X234300Y-124800D01*
X233600Y-124667D01*
X232900Y-124933D01*
X232300Y-125467D01*
X231900Y-126267D01*
X231700Y-127333D01*
X231900Y-128400D01*
X232300Y-129200D01*
X232900Y-129733D01*
X233600Y-130000D01*
X234300Y-129867D01*
X234900Y-129467D01*
X235300Y-128934D01*
G01X239800Y-130000D02*
Y-124667D01*
G01Y-126000D02*
X240200Y-125333D01*
X240800Y-124800D01*
X241600Y-124667D01*
X242300Y-124800D01*
X242900Y-125333D01*
X243200Y-126267D01*
Y-130000D01*
G01X251300Y-122000D02*
Y-130000D01*
G01Y-128800D02*
X250900Y-129467D01*
X250300Y-129867D01*
X249600Y-130000D01*
X248800Y-129733D01*
X248200Y-129067D01*
X247800Y-128267D01*
X247700Y-127333D01*
X247800Y-126400D01*
X248200Y-125600D01*
X248800Y-124933D01*
X249600Y-124667D01*
X250300Y-124800D01*
X250800Y-125067D01*
X251300Y-125600D01*
G01X255400Y-132400D02*
X256000Y-132667D01*
X256800Y-132400D01*
X257300Y-131867D01*
X257700Y-131200D01*
X258300Y-129067D01*
X259600Y-124667D01*
G01X256400D02*
X258300Y-129067D01*
G01X238356Y694796D02*
Y697896D01*
X239276D01*
X239583Y697741D01*
X239813Y697379D01*
X239890Y696966D01*
X239813Y696553D01*
X239621Y696243D01*
X239276Y696088D01*
X238356D01*
G01X241456Y694796D02*
Y697896D01*
X242415D01*
X242721Y697741D01*
X242913Y697534D01*
X242990Y697121D01*
X242913Y696708D01*
X242683Y696449D01*
X242415Y696294D01*
X241456D01*
G01X242415D02*
X242990Y694796D01*
G01X246090D02*
X244556D01*
Y697896D01*
X246090D01*
G01X245476Y696398D02*
X244556D01*
G01X247618Y695209D02*
X247925Y694951D01*
X248270Y694796D01*
X248576D01*
X248883Y694951D01*
X249113Y695209D01*
X249228Y695571D01*
X249151Y695933D01*
X248960Y696243D01*
X248615Y696449D01*
X248155Y696553D01*
X247886Y696759D01*
X247771Y697121D01*
X247848Y697483D01*
X248040Y697741D01*
X248308Y697896D01*
X248576D01*
X248845Y697793D01*
X249075Y697534D01*
G01X250718Y695209D02*
X251025Y694951D01*
X251370Y694796D01*
X251676D01*
X251983Y694951D01*
X252213Y695209D01*
X252328Y695571D01*
X252251Y695933D01*
X252060Y696243D01*
X251715Y696449D01*
X251255Y696553D01*
X250986Y696759D01*
X250871Y697121D01*
X250948Y697483D01*
X251140Y697741D01*
X251408Y697896D01*
X251676D01*
X251945Y697793D01*
X252175Y697534D01*
G01X254125Y695829D02*
X255121D01*
G01X256995Y694796D02*
Y697896D01*
X258451D01*
G01X257915Y696398D02*
X256995D01*
G01X260363Y697896D02*
X261283D01*
G01X260823D02*
Y694796D01*
G01X260363D02*
X261283D01*
G01X263923Y697896D02*
Y694796D01*
G01X263041Y697896D02*
X264805D01*
G01X221026Y770104D02*
X220106D01*
G01X220604Y769432D02*
Y770775D01*
G01X220315Y776230D02*
X220085Y776385D01*
X219817Y776488D01*
X219510D01*
X219165Y776333D01*
X218897Y776075D01*
X218705Y775765D01*
X218552Y775248D01*
X218514Y774783D01*
X218590Y774318D01*
X218705Y774008D01*
X218935Y773698D01*
X219204Y773491D01*
X219472Y773388D01*
X219740D01*
X220009Y773491D01*
X220239Y773646D01*
X220430Y773853D01*
G01X223339Y773388D02*
X221805D01*
Y776488D01*
X223339D01*
G01X222725Y774990D02*
X221805D01*
G01X225672Y773388D02*
Y776488D01*
X225212Y775868D01*
G01Y773388D02*
X226132D01*
G01X228772Y776488D02*
X228465Y776385D01*
X228235Y776126D01*
X228082Y775816D01*
X227967Y775403D01*
X227929Y774938D01*
X227967Y774473D01*
X228082Y774060D01*
X228235Y773750D01*
X228465Y773491D01*
X228772Y773388D01*
X229079Y773491D01*
X229309Y773750D01*
X229462Y774060D01*
X229577Y774473D01*
X229615Y774938D01*
X229577Y775403D01*
X229462Y775816D01*
X229309Y776126D01*
X229079Y776385D01*
X228772Y776488D01*
G01X221505Y853619D02*
X220585D01*
G01X221083Y852947D02*
Y854290D01*
G01X220303Y867801D02*
Y870901D01*
X221223D01*
X221530Y870746D01*
X221760Y870384D01*
X221837Y869971D01*
X221760Y869558D01*
X221568Y869248D01*
X221223Y869093D01*
X220303D01*
G01X223403Y867801D02*
Y870901D01*
X224362D01*
X224668Y870746D01*
X224860Y870539D01*
X224937Y870126D01*
X224860Y869713D01*
X224630Y869454D01*
X224362Y869299D01*
X223403D01*
G01X224362D02*
X224937Y867801D01*
G01X228037D02*
X226503D01*
Y870901D01*
X228037D01*
G01X227423Y869403D02*
X226503D01*
G01X229565Y868214D02*
X229872Y867956D01*
X230217Y867801D01*
X230523D01*
X230830Y867956D01*
X231060Y868214D01*
X231175Y868576D01*
X231098Y868938D01*
X230907Y869248D01*
X230562Y869454D01*
X230102Y869558D01*
X229833Y869764D01*
X229718Y870126D01*
X229795Y870488D01*
X229987Y870746D01*
X230255Y870901D01*
X230523D01*
X230792Y870798D01*
X231022Y870539D01*
G01X232665Y868214D02*
X232972Y867956D01*
X233317Y867801D01*
X233623D01*
X233930Y867956D01*
X234160Y868214D01*
X234275Y868576D01*
X234198Y868938D01*
X234007Y869248D01*
X233662Y869454D01*
X233202Y869558D01*
X232933Y869764D01*
X232818Y870126D01*
X232895Y870488D01*
X233087Y870746D01*
X233355Y870901D01*
X233623D01*
X233892Y870798D01*
X234122Y870539D01*
G01X236072Y868834D02*
X237068D01*
G01X238942Y867801D02*
Y870901D01*
X240398D01*
G01X239862Y869403D02*
X238942D01*
G01X242310Y870901D02*
X243230D01*
G01X242770D02*
Y867801D01*
G01X242310D02*
X243230D01*
G01X245870Y870901D02*
Y867801D01*
G01X244988Y870901D02*
X246752D01*
G01X226210Y942421D02*
X225290D01*
G01X225788Y941749D02*
Y943092D01*
G01X224958Y949371D02*
X224728Y949526D01*
X224460Y949629D01*
X224153D01*
X223808Y949474D01*
X223540Y949216D01*
X223348Y948906D01*
X223195Y948389D01*
X223157Y947924D01*
X223233Y947459D01*
X223348Y947149D01*
X223578Y946839D01*
X223847Y946632D01*
X224115Y946529D01*
X224383D01*
X224652Y946632D01*
X224882Y946787D01*
X225073Y946994D01*
G01X227982Y946529D02*
X226448D01*
Y949629D01*
X227982D01*
G01X227368Y948131D02*
X226448D01*
G01X230315Y946529D02*
Y949629D01*
X229855Y949009D01*
G01Y946529D02*
X230775D01*
G01X232687Y949112D02*
X232917Y949422D01*
X233185Y949577D01*
X233492Y949629D01*
X233875Y949526D01*
X234143Y949267D01*
X234220Y948957D01*
X234182Y948647D01*
X234028Y948389D01*
X233262Y947872D01*
X232917Y947511D01*
X232687Y946994D01*
X232610Y946529D01*
X234220D01*
G01X221557Y1034021D02*
X220637D01*
G01X221135Y1033349D02*
Y1034692D01*
G01X235988Y1045433D02*
Y1048533D01*
X236908D01*
X237215Y1048378D01*
X237445Y1048016D01*
X237522Y1047603D01*
X237445Y1047190D01*
X237253Y1046880D01*
X236908Y1046725D01*
X235988D01*
G01X239088Y1045433D02*
Y1048533D01*
X240047D01*
X240353Y1048378D01*
X240545Y1048171D01*
X240622Y1047758D01*
X240545Y1047345D01*
X240315Y1047086D01*
X240047Y1046931D01*
X239088D01*
G01X240047D02*
X240622Y1045433D01*
G01X243722D02*
X242188D01*
Y1048533D01*
X243722D01*
G01X243108Y1047035D02*
X242188D01*
G01X245250Y1045846D02*
X245557Y1045588D01*
X245902Y1045433D01*
X246208D01*
X246515Y1045588D01*
X246745Y1045846D01*
X246860Y1046208D01*
X246783Y1046570D01*
X246592Y1046880D01*
X246247Y1047086D01*
X245787Y1047190D01*
X245518Y1047396D01*
X245403Y1047758D01*
X245480Y1048120D01*
X245672Y1048378D01*
X245940Y1048533D01*
X246208D01*
X246477Y1048430D01*
X246707Y1048171D01*
G01X248350Y1045846D02*
X248657Y1045588D01*
X249002Y1045433D01*
X249308D01*
X249615Y1045588D01*
X249845Y1045846D01*
X249960Y1046208D01*
X249883Y1046570D01*
X249692Y1046880D01*
X249347Y1047086D01*
X248887Y1047190D01*
X248618Y1047396D01*
X248503Y1047758D01*
X248580Y1048120D01*
X248772Y1048378D01*
X249040Y1048533D01*
X249308D01*
X249577Y1048430D01*
X249807Y1048171D01*
G01X251757Y1046466D02*
X252753D01*
G01X254627Y1045433D02*
Y1048533D01*
X256083D01*
G01X255547Y1047035D02*
X254627D01*
G01X257995Y1048533D02*
X258915D01*
G01X258455D02*
Y1045433D01*
G01X257995D02*
X258915D01*
G01X261555Y1048533D02*
Y1045433D01*
G01X260673Y1048533D02*
X262437D01*
G01X219804Y1207200D02*
X218884D01*
G01X219382Y1206528D02*
Y1207871D01*
G01X229283Y1393684D02*
Y1396784D01*
X230203D01*
X230510Y1396629D01*
X230740Y1396267D01*
X230817Y1395854D01*
X230740Y1395441D01*
X230548Y1395131D01*
X230203Y1394976D01*
X229283D01*
G01X232383Y1393684D02*
Y1396784D01*
X233342D01*
X233648Y1396629D01*
X233840Y1396422D01*
X233917Y1396009D01*
X233840Y1395596D01*
X233610Y1395337D01*
X233342Y1395182D01*
X232383D01*
G01X233342D02*
X233917Y1393684D01*
G01X237017D02*
X235483D01*
Y1396784D01*
X237017D01*
G01X236403Y1395286D02*
X235483D01*
G01X238545Y1394097D02*
X238852Y1393839D01*
X239197Y1393684D01*
X239503D01*
X239810Y1393839D01*
X240040Y1394097D01*
X240155Y1394459D01*
X240078Y1394821D01*
X239887Y1395131D01*
X239542Y1395337D01*
X239082Y1395441D01*
X238813Y1395647D01*
X238698Y1396009D01*
X238775Y1396371D01*
X238967Y1396629D01*
X239235Y1396784D01*
X239503D01*
X239772Y1396681D01*
X240002Y1396422D01*
G01X241645Y1394097D02*
X241952Y1393839D01*
X242297Y1393684D01*
X242603D01*
X242910Y1393839D01*
X243140Y1394097D01*
X243255Y1394459D01*
X243178Y1394821D01*
X242987Y1395131D01*
X242642Y1395337D01*
X242182Y1395441D01*
X241913Y1395647D01*
X241798Y1396009D01*
X241875Y1396371D01*
X242067Y1396629D01*
X242335Y1396784D01*
X242603D01*
X242872Y1396681D01*
X243102Y1396422D01*
G01X245052Y1394717D02*
X246048D01*
G01X247922Y1393684D02*
Y1396784D01*
X249378D01*
G01X248842Y1395286D02*
X247922D01*
G01X251290Y1396784D02*
X252210D01*
G01X251750D02*
Y1393684D01*
G01X251290D02*
X252210D01*
G01X254850Y1396784D02*
Y1393684D01*
G01X253968Y1396784D02*
X255732D01*
G01X234561Y1569356D02*
Y1572456D01*
X235481D01*
X235788Y1572301D01*
X236018Y1571939D01*
X236095Y1571526D01*
X236018Y1571113D01*
X235826Y1570803D01*
X235481Y1570648D01*
X234561D01*
G01X237661Y1569356D02*
Y1572456D01*
X238620D01*
X238926Y1572301D01*
X239118Y1572094D01*
X239195Y1571681D01*
X239118Y1571268D01*
X238888Y1571009D01*
X238620Y1570854D01*
X237661D01*
G01X238620D02*
X239195Y1569356D01*
G01X242295D02*
X240761D01*
Y1572456D01*
X242295D01*
G01X241681Y1570958D02*
X240761D01*
G01X243823Y1569769D02*
X244130Y1569511D01*
X244475Y1569356D01*
X244781D01*
X245088Y1569511D01*
X245318Y1569769D01*
X245433Y1570131D01*
X245356Y1570493D01*
X245165Y1570803D01*
X244820Y1571009D01*
X244360Y1571113D01*
X244091Y1571319D01*
X243976Y1571681D01*
X244053Y1572043D01*
X244245Y1572301D01*
X244513Y1572456D01*
X244781D01*
X245050Y1572353D01*
X245280Y1572094D01*
G01X246923Y1569769D02*
X247230Y1569511D01*
X247575Y1569356D01*
X247881D01*
X248188Y1569511D01*
X248418Y1569769D01*
X248533Y1570131D01*
X248456Y1570493D01*
X248265Y1570803D01*
X247920Y1571009D01*
X247460Y1571113D01*
X247191Y1571319D01*
X247076Y1571681D01*
X247153Y1572043D01*
X247345Y1572301D01*
X247613Y1572456D01*
X247881D01*
X248150Y1572353D01*
X248380Y1572094D01*
G01X250330Y1570389D02*
X251326D01*
G01X253200Y1569356D02*
Y1572456D01*
X254656D01*
G01X254120Y1570958D02*
X253200D01*
G01X256568Y1572456D02*
X257488D01*
G01X257028D02*
Y1569356D01*
G01X256568D02*
X257488D01*
G01X260128Y1572456D02*
Y1569356D01*
G01X259246Y1572456D02*
X261010D01*
G01X220069Y1732318D02*
X219149D01*
G01X219647Y1731646D02*
Y1732989D01*
G01X239996Y1744063D02*
Y1747163D01*
X240916D01*
X241223Y1747008D01*
X241453Y1746646D01*
X241530Y1746233D01*
X241453Y1745820D01*
X241261Y1745510D01*
X240916Y1745355D01*
X239996D01*
G01X243096Y1744063D02*
Y1747163D01*
X244055D01*
X244361Y1747008D01*
X244553Y1746801D01*
X244630Y1746388D01*
X244553Y1745975D01*
X244323Y1745716D01*
X244055Y1745561D01*
X243096D01*
G01X244055D02*
X244630Y1744063D01*
G01X247730D02*
X246196D01*
Y1747163D01*
X247730D01*
G01X247116Y1745665D02*
X246196D01*
G01X249258Y1744476D02*
X249565Y1744218D01*
X249910Y1744063D01*
X250216D01*
X250523Y1744218D01*
X250753Y1744476D01*
X250868Y1744838D01*
X250791Y1745200D01*
X250600Y1745510D01*
X250255Y1745716D01*
X249795Y1745820D01*
X249526Y1746026D01*
X249411Y1746388D01*
X249488Y1746750D01*
X249680Y1747008D01*
X249948Y1747163D01*
X250216D01*
X250485Y1747060D01*
X250715Y1746801D01*
G01X252358Y1744476D02*
X252665Y1744218D01*
X253010Y1744063D01*
X253316D01*
X253623Y1744218D01*
X253853Y1744476D01*
X253968Y1744838D01*
X253891Y1745200D01*
X253700Y1745510D01*
X253355Y1745716D01*
X252895Y1745820D01*
X252626Y1746026D01*
X252511Y1746388D01*
X252588Y1746750D01*
X252780Y1747008D01*
X253048Y1747163D01*
X253316D01*
X253585Y1747060D01*
X253815Y1746801D01*
G01X255765Y1745096D02*
X256761D01*
G01X258635Y1744063D02*
Y1747163D01*
X260091D01*
G01X259555Y1745665D02*
X258635D01*
G01X262003Y1747163D02*
X262923D01*
G01X262463D02*
Y1744063D01*
G01X262003D02*
X262923D01*
G01X265563Y1747163D02*
Y1744063D01*
G01X264681Y1747163D02*
X266445D01*
G01X219992Y1824194D02*
X219072D01*
G01X219570Y1823522D02*
Y1824865D01*
G01X220411Y1999697D02*
X219491D01*
G01X219989Y1999025D02*
Y2000368D01*
G01X220890Y2039505D02*
X219970D01*
G01X220468Y2038833D02*
Y2040176D01*
G01X259200Y122623D02*
Y125723D01*
X260159D01*
X260465Y125568D01*
X260657Y125361D01*
X260734Y124948D01*
X260657Y124535D01*
X260427Y124276D01*
X260159Y124121D01*
X259200D01*
G01X260159D02*
X260734Y122623D01*
G01X263067D02*
Y125723D01*
X262607Y125103D01*
G01Y122623D02*
X263527D01*
G01X266167D02*
Y125723D01*
X265707Y125103D01*
G01Y122623D02*
X266627D01*
G01X269267D02*
Y125723D01*
X268807Y125103D01*
G01Y122623D02*
X269727D01*
G01X266210Y126628D02*
X260010D01*
Y129828D01*
X266210D01*
Y126628D01*
G01X258104Y109215D02*
Y112315D01*
X259063D01*
X259369Y112160D01*
X259561Y111953D01*
X259638Y111540D01*
X259561Y111127D01*
X259331Y110868D01*
X259063Y110713D01*
X258104D01*
G01X259063D02*
X259638Y109215D01*
G01X261971D02*
Y112315D01*
X261511Y111695D01*
G01Y109215D02*
X262431D01*
G01X265071D02*
Y112315D01*
X264611Y111695D01*
G01Y109215D02*
X265531D01*
G01X267443Y111798D02*
X267673Y112108D01*
X267941Y112263D01*
X268248Y112315D01*
X268631Y112212D01*
X268899Y111953D01*
X268976Y111643D01*
X268938Y111333D01*
X268784Y111075D01*
X268018Y110558D01*
X267673Y110197D01*
X267443Y109680D01*
X267366Y109215D01*
X268976D01*
G01X266454Y113959D02*
X260254D01*
Y117159D01*
X266454D01*
Y113959D01*
G01X264807Y456200D02*
Y459300D01*
X265766D01*
X266072Y459145D01*
X266264Y458938D01*
X266341Y458525D01*
X266264Y458112D01*
X266034Y457853D01*
X265766Y457698D01*
X264807D01*
G01X265766D02*
X266341Y456200D01*
G01X268674D02*
Y459300D01*
X268214Y458680D01*
G01Y456200D02*
X269134D01*
G01X271774D02*
Y459300D01*
X271314Y458680D01*
G01Y456200D02*
X272234D01*
G01X274146Y457492D02*
X274414Y457853D01*
X274644Y458060D01*
X274951Y458163D01*
X275219Y458060D01*
X275411Y457853D01*
X275564Y457543D01*
X275602Y457182D01*
X275564Y456872D01*
X275411Y456562D01*
X275181Y456303D01*
X274912Y456200D01*
X274606Y456303D01*
X274337Y456613D01*
X274184Y457078D01*
X274146Y457595D01*
X274222Y458267D01*
X274337Y458628D01*
X274529Y458990D01*
X274797Y459248D01*
X275066Y459300D01*
X275334Y459197D01*
X275526Y458938D01*
G01X260743Y477444D02*
Y480544D01*
X261702D01*
X262008Y480389D01*
X262200Y480182D01*
X262277Y479769D01*
X262200Y479356D01*
X261970Y479097D01*
X261702Y478942D01*
X260743D01*
G01X261702D02*
X262277Y477444D01*
G01X264610D02*
Y480544D01*
X264150Y479924D01*
G01Y477444D02*
X265070D01*
G01X267710D02*
Y480544D01*
X267250Y479924D01*
G01Y477444D02*
X268170D01*
G01X269967Y477909D02*
X270197Y477651D01*
X270465Y477496D01*
X270810Y477444D01*
X271155Y477547D01*
X271423Y477754D01*
X271615Y478116D01*
X271653Y478529D01*
X271577Y478942D01*
X271385Y479201D01*
X271117Y479407D01*
X270848Y479459D01*
X270580Y479407D01*
X270235Y479201D01*
X270350Y480544D01*
X271385D01*
G01X263737Y805150D02*
Y808250D01*
X264696D01*
X265002Y808095D01*
X265194Y807888D01*
X265271Y807475D01*
X265194Y807062D01*
X264964Y806803D01*
X264696Y806648D01*
X263737D01*
G01X264696D02*
X265271Y805150D01*
G01X267604D02*
Y808250D01*
X267144Y807630D01*
G01Y805150D02*
X268064D01*
G01X269976Y807733D02*
X270206Y808043D01*
X270474Y808198D01*
X270781Y808250D01*
X271164Y808147D01*
X271432Y807888D01*
X271509Y807578D01*
X271471Y807268D01*
X271317Y807010D01*
X270551Y806493D01*
X270206Y806132D01*
X269976Y805615D01*
X269899Y805150D01*
X271509D01*
G01X273804Y808250D02*
X273497Y808147D01*
X273267Y807888D01*
X273114Y807578D01*
X272999Y807165D01*
X272961Y806700D01*
X272999Y806235D01*
X273114Y805822D01*
X273267Y805512D01*
X273497Y805253D01*
X273804Y805150D01*
X274111Y805253D01*
X274341Y805512D01*
X274494Y805822D01*
X274609Y806235D01*
X274647Y806700D01*
X274609Y807165D01*
X274494Y807578D01*
X274341Y807888D01*
X274111Y808147D01*
X273804Y808250D01*
G01X259209Y826039D02*
Y829139D01*
X260168D01*
X260474Y828984D01*
X260666Y828777D01*
X260743Y828364D01*
X260666Y827951D01*
X260436Y827692D01*
X260168Y827537D01*
X259209D01*
G01X260168D02*
X260743Y826039D01*
G01X263076D02*
Y829139D01*
X262616Y828519D01*
G01Y826039D02*
X263536D01*
G01X266176D02*
Y829139D01*
X265716Y828519D01*
G01Y826039D02*
X266636D01*
G01X268624Y826401D02*
X268893Y826142D01*
X269199Y826039D01*
X269506Y826142D01*
X269774Y826452D01*
X269966Y826917D01*
X270043Y827382D01*
Y827951D01*
X269966Y828416D01*
X269774Y828829D01*
X269544Y829036D01*
X269276Y829139D01*
X268969Y829036D01*
X268739Y828829D01*
X268586Y828519D01*
X268509Y828106D01*
X268586Y827744D01*
X268778Y827382D01*
X269008Y827176D01*
X269276Y827124D01*
X269583Y827227D01*
X269813Y827486D01*
X270043Y827951D01*
G01X265700Y822004D02*
X259500D01*
Y825204D01*
X265700D01*
Y822004D01*
G01X265860Y810570D02*
X259660D01*
Y813770D01*
X265860D01*
Y810570D01*
G01X263689Y1559475D02*
X263534Y1559245D01*
X263431Y1558977D01*
Y1558670D01*
X263586Y1558325D01*
X263844Y1558057D01*
X264154Y1557865D01*
X264671Y1557712D01*
X265136Y1557674D01*
X265601Y1557750D01*
X265911Y1557865D01*
X266221Y1558095D01*
X266428Y1558364D01*
X266531Y1558632D01*
Y1558900D01*
X266428Y1559169D01*
X266273Y1559399D01*
X266066Y1559590D01*
G01X266531Y1561655D02*
X265859Y1561732D01*
X265291Y1561847D01*
X264774Y1562000D01*
X264206Y1562192D01*
X263431Y1562499D01*
Y1560965D01*
G01Y1564832D02*
X263534Y1564525D01*
X263793Y1564295D01*
X264103Y1564142D01*
X264516Y1564027D01*
X264981Y1563989D01*
X265446Y1564027D01*
X265859Y1564142D01*
X266169Y1564295D01*
X266428Y1564525D01*
X266531Y1564832D01*
X266428Y1565139D01*
X266169Y1565369D01*
X265859Y1565522D01*
X265446Y1565637D01*
X264981Y1565675D01*
X264516Y1565637D01*
X264103Y1565522D01*
X263793Y1565369D01*
X263534Y1565139D01*
X263431Y1564832D01*
G01X338582Y127165D02*
G03I-31496J0D01*
G01X284586Y167839D02*
X281586D01*
G01X281486Y164739D02*
Y170939D01*
X284686D01*
Y164739D01*
X281486D01*
G01X288920Y167839D02*
X285920D01*
G01X285820Y164739D02*
Y170939D01*
X289020D01*
Y164739D01*
X285820D01*
G01X293443Y167839D02*
X290443D01*
G01X290343Y164739D02*
Y170939D01*
X293543D01*
Y164739D01*
X290343D01*
G01X274385Y248933D02*
X274230Y248703D01*
X274127Y248435D01*
Y248128D01*
X274282Y247783D01*
X274540Y247515D01*
X274850Y247323D01*
X275367Y247170D01*
X275832Y247132D01*
X276297Y247208D01*
X276607Y247323D01*
X276917Y247553D01*
X277124Y247822D01*
X277227Y248090D01*
Y248358D01*
X277124Y248627D01*
X276969Y248857D01*
X276762Y249048D01*
G01X276865Y250538D02*
X277124Y250807D01*
X277227Y251113D01*
X277124Y251420D01*
X276814Y251688D01*
X276349Y251880D01*
X275884Y251957D01*
X275315D01*
X274850Y251880D01*
X274437Y251688D01*
X274230Y251458D01*
X274127Y251190D01*
X274230Y250883D01*
X274437Y250653D01*
X274747Y250500D01*
X275160Y250423D01*
X275522Y250500D01*
X275884Y250692D01*
X276090Y250922D01*
X276142Y251190D01*
X276039Y251497D01*
X275780Y251727D01*
X275315Y251957D01*
G01X275117Y236864D02*
X278117D01*
G01X278217Y239964D02*
Y233764D01*
X275017D01*
Y239964D01*
X278217D01*
G01X279420Y248933D02*
X279265Y248703D01*
X279162Y248435D01*
Y248128D01*
X279317Y247783D01*
X279575Y247515D01*
X279885Y247323D01*
X280402Y247170D01*
X280867Y247132D01*
X281332Y247208D01*
X281642Y247323D01*
X281952Y247553D01*
X282159Y247822D01*
X282262Y248090D01*
Y248358D01*
X282159Y248627D01*
X282004Y248857D01*
X281797Y249048D01*
G01X282262Y251190D02*
X279162D01*
X279782Y250730D01*
G01X282262D02*
Y251650D01*
G01X279162Y254290D02*
X279265Y253983D01*
X279524Y253753D01*
X279834Y253600D01*
X280247Y253485D01*
X280712Y253447D01*
X281177Y253485D01*
X281590Y253600D01*
X281900Y253753D01*
X282159Y253983D01*
X282262Y254290D01*
X282159Y254597D01*
X281900Y254827D01*
X281590Y254980D01*
X281177Y255095D01*
X280712Y255133D01*
X280247Y255095D01*
X279834Y254980D01*
X279524Y254827D01*
X279265Y254597D01*
X279162Y254290D01*
G01X279693Y236864D02*
X282693D01*
G01X282793Y239964D02*
Y233764D01*
X279593D01*
Y239964D01*
X282793D01*
G01X269852Y248933D02*
X269697Y248703D01*
X269594Y248435D01*
Y248128D01*
X269749Y247783D01*
X270007Y247515D01*
X270317Y247323D01*
X270834Y247170D01*
X271299Y247132D01*
X271764Y247208D01*
X272074Y247323D01*
X272384Y247553D01*
X272591Y247822D01*
X272694Y248090D01*
Y248358D01*
X272591Y248627D01*
X272436Y248857D01*
X272229Y249048D01*
G01X272694Y251190D02*
X272642Y251458D01*
X272487Y251765D01*
X272229Y251957D01*
X271867Y252033D01*
X271506Y251957D01*
X271196Y251727D01*
X271041Y251382D01*
Y250998D01*
X270937Y250768D01*
X270679Y250577D01*
X270317Y250500D01*
X269956Y250615D01*
X269697Y250883D01*
X269594Y251190D01*
X269697Y251497D01*
X269956Y251765D01*
X270317Y251880D01*
X270679Y251803D01*
X270937Y251612D01*
X271041Y251382D01*
Y250998D01*
X271196Y250653D01*
X271506Y250423D01*
X271867Y250347D01*
X272229Y250423D01*
X272487Y250615D01*
X272642Y250922D01*
X272694Y251190D01*
G01X273847Y243964D02*
Y233764D01*
X269247D01*
Y243964D01*
X273847D01*
G01Y238864D02*
X269247D01*
G01X278978Y328035D02*
X278823Y327805D01*
X278720Y327537D01*
Y327230D01*
X278875Y326885D01*
X279133Y326617D01*
X279443Y326425D01*
X279960Y326272D01*
X280425Y326234D01*
X280890Y326310D01*
X281200Y326425D01*
X281510Y326655D01*
X281717Y326924D01*
X281820Y327192D01*
Y327460D01*
X281717Y327729D01*
X281562Y327959D01*
X281355Y328150D01*
G01X279237Y329564D02*
X278927Y329794D01*
X278772Y330062D01*
X278720Y330369D01*
X278823Y330752D01*
X279082Y331020D01*
X279392Y331097D01*
X279702Y331059D01*
X279960Y330905D01*
X280477Y330139D01*
X280838Y329794D01*
X281355Y329564D01*
X281820Y329487D01*
Y331097D01*
G01Y333392D02*
X278720D01*
X279340Y332932D01*
G01X281820D02*
Y333852D01*
G01X282574Y343092D02*
X279574D01*
G01X279474Y339992D02*
Y346192D01*
X282674D01*
Y339992D01*
X279474D01*
G01X288811Y327892D02*
X288656Y327662D01*
X288553Y327394D01*
Y327087D01*
X288708Y326742D01*
X288966Y326474D01*
X289276Y326282D01*
X289793Y326129D01*
X290258Y326091D01*
X290723Y326167D01*
X291033Y326282D01*
X291343Y326512D01*
X291550Y326781D01*
X291653Y327049D01*
Y327317D01*
X291550Y327586D01*
X291395Y327816D01*
X291188Y328007D01*
G01X291653Y330149D02*
X288553D01*
X289173Y329689D01*
G01X291653D02*
Y330609D01*
G01X291291Y332597D02*
X291550Y332866D01*
X291653Y333172D01*
X291550Y333479D01*
X291240Y333747D01*
X290775Y333939D01*
X290310Y334016D01*
X289741D01*
X289276Y333939D01*
X288863Y333747D01*
X288656Y333517D01*
X288553Y333249D01*
X288656Y332942D01*
X288863Y332712D01*
X289173Y332559D01*
X289586Y332482D01*
X289948Y332559D01*
X290310Y332751D01*
X290516Y332981D01*
X290568Y333249D01*
X290465Y333556D01*
X290206Y333786D01*
X289741Y334016D01*
G01X291395Y343092D02*
X288395D01*
G01X288295Y339992D02*
Y346192D01*
X291495D01*
Y339992D01*
X288295D01*
G01X284004Y327751D02*
X283849Y327521D01*
X283746Y327253D01*
Y326946D01*
X283901Y326601D01*
X284159Y326333D01*
X284469Y326141D01*
X284986Y325988D01*
X285451Y325950D01*
X285916Y326026D01*
X286226Y326141D01*
X286536Y326371D01*
X286743Y326640D01*
X286846Y326908D01*
Y327176D01*
X286743Y327445D01*
X286588Y327675D01*
X286381Y327866D01*
G01X284263Y329280D02*
X283953Y329510D01*
X283798Y329778D01*
X283746Y330085D01*
X283849Y330468D01*
X284108Y330736D01*
X284418Y330813D01*
X284728Y330775D01*
X284986Y330621D01*
X285503Y329855D01*
X285864Y329510D01*
X286381Y329280D01*
X286846Y329203D01*
Y330813D01*
G01X283746Y333108D02*
X283849Y332801D01*
X284108Y332571D01*
X284418Y332418D01*
X284831Y332303D01*
X285296Y332265D01*
X285761Y332303D01*
X286174Y332418D01*
X286484Y332571D01*
X286743Y332801D01*
X286846Y333108D01*
X286743Y333415D01*
X286484Y333645D01*
X286174Y333798D01*
X285761Y333913D01*
X285296Y333951D01*
X284831Y333913D01*
X284418Y333798D01*
X284108Y333645D01*
X283849Y333415D01*
X283746Y333108D01*
G01X287013Y343092D02*
X284013D01*
G01X283913Y339992D02*
Y346192D01*
X287113D01*
Y339992D01*
X283913D01*
G01X289502Y412440D02*
X292502D01*
G01X292602Y415540D02*
Y409340D01*
X289402D01*
Y415540D01*
X292602D01*
G01X285165Y412440D02*
X288165D01*
G01X288265Y415540D02*
Y409340D01*
X285065D01*
Y415540D01*
X288265D01*
G01X283869Y419540D02*
Y409340D01*
X279269D01*
Y419540D01*
X283869D01*
G01Y414440D02*
X279269D01*
G01X289873Y424993D02*
X289718Y424763D01*
X289615Y424495D01*
Y424188D01*
X289770Y423843D01*
X290028Y423575D01*
X290338Y423383D01*
X290855Y423230D01*
X291320Y423192D01*
X291785Y423268D01*
X292095Y423383D01*
X292405Y423613D01*
X292612Y423882D01*
X292715Y424150D01*
Y424418D01*
X292612Y424687D01*
X292457Y424917D01*
X292250Y425108D01*
G01X292715Y427250D02*
X289615D01*
X290235Y426790D01*
G01X292715D02*
Y427710D01*
G01Y430273D02*
X292043Y430350D01*
X291475Y430465D01*
X290958Y430618D01*
X290390Y430810D01*
X289615Y431117D01*
Y429583D01*
G01X284758Y424993D02*
X284603Y424763D01*
X284500Y424495D01*
Y424188D01*
X284655Y423843D01*
X284913Y423575D01*
X285223Y423383D01*
X285740Y423230D01*
X286205Y423192D01*
X286670Y423268D01*
X286980Y423383D01*
X287290Y423613D01*
X287497Y423882D01*
X287600Y424150D01*
Y424418D01*
X287497Y424687D01*
X287342Y424917D01*
X287135Y425108D01*
G01X287600Y427250D02*
X284500D01*
X285120Y426790D01*
G01X287600D02*
Y427710D01*
G01X286308Y429622D02*
X285947Y429890D01*
X285740Y430120D01*
X285637Y430427D01*
X285740Y430695D01*
X285947Y430887D01*
X286257Y431040D01*
X286618Y431078D01*
X286928Y431040D01*
X287238Y430887D01*
X287497Y430657D01*
X287600Y430388D01*
X287497Y430082D01*
X287187Y429813D01*
X286722Y429660D01*
X286205Y429622D01*
X285533Y429698D01*
X285172Y429813D01*
X284810Y430005D01*
X284552Y430273D01*
X284500Y430542D01*
X284603Y430810D01*
X284862Y431002D01*
G01X280154Y424993D02*
X279999Y424763D01*
X279896Y424495D01*
Y424188D01*
X280051Y423843D01*
X280309Y423575D01*
X280619Y423383D01*
X281136Y423230D01*
X281601Y423192D01*
X282066Y423268D01*
X282376Y423383D01*
X282686Y423613D01*
X282893Y423882D01*
X282996Y424150D01*
Y424418D01*
X282893Y424687D01*
X282738Y424917D01*
X282531Y425108D01*
G01X282996Y427250D02*
X279896D01*
X280516Y426790D01*
G01X282996D02*
Y427710D01*
G01X282531Y429507D02*
X282789Y429737D01*
X282944Y430005D01*
X282996Y430350D01*
X282893Y430695D01*
X282686Y430963D01*
X282324Y431155D01*
X281911Y431193D01*
X281498Y431117D01*
X281239Y430925D01*
X281033Y430657D01*
X280981Y430388D01*
X281033Y430120D01*
X281239Y429775D01*
X279896Y429890D01*
Y430925D01*
G01X273636Y461499D02*
X267436D01*
Y464699D01*
X273636D01*
Y461499D01*
G01X338582Y477165D02*
G03I-31496J0D01*
G01X273563Y472077D02*
X267363D01*
Y475277D01*
X273563D01*
Y472077D01*
G01X268544Y490278D02*
Y493378D01*
G01X270154D02*
Y490278D01*
G01Y491828D02*
X268544D01*
G01X271797Y490640D02*
X272066Y490381D01*
X272372Y490278D01*
X272679Y490381D01*
X272947Y490691D01*
X273139Y491156D01*
X273216Y491621D01*
Y492190D01*
X273139Y492655D01*
X272947Y493068D01*
X272717Y493275D01*
X272449Y493378D01*
X272142Y493275D01*
X271912Y493068D01*
X271759Y492758D01*
X271682Y492345D01*
X271759Y491983D01*
X271951Y491621D01*
X272181Y491415D01*
X272449Y491363D01*
X272756Y491466D01*
X272986Y491725D01*
X273216Y492190D01*
G01X277219Y504409D02*
X277064Y504179D01*
X276961Y503911D01*
Y503604D01*
X277116Y503259D01*
X277374Y502991D01*
X277684Y502799D01*
X278201Y502646D01*
X278666Y502608D01*
X279131Y502684D01*
X279441Y502799D01*
X279751Y503029D01*
X279958Y503298D01*
X280061Y503566D01*
Y503834D01*
X279958Y504103D01*
X279803Y504333D01*
X279596Y504524D01*
G01X277478Y505938D02*
X277168Y506168D01*
X277013Y506436D01*
X276961Y506743D01*
X277064Y507126D01*
X277323Y507394D01*
X277633Y507471D01*
X277943Y507433D01*
X278201Y507279D01*
X278718Y506513D01*
X279079Y506168D01*
X279596Y505938D01*
X280061Y505861D01*
Y507471D01*
G01X278769Y509038D02*
X278408Y509306D01*
X278201Y509536D01*
X278098Y509843D01*
X278201Y510111D01*
X278408Y510303D01*
X278718Y510456D01*
X279079Y510494D01*
X279389Y510456D01*
X279699Y510303D01*
X279958Y510073D01*
X280061Y509804D01*
X279958Y509498D01*
X279648Y509229D01*
X279183Y509076D01*
X278666Y509038D01*
X277994Y509114D01*
X277633Y509229D01*
X277271Y509421D01*
X277013Y509689D01*
X276961Y509958D01*
X277064Y510226D01*
X277323Y510418D01*
G01X276805Y514394D02*
Y520594D01*
X280005D01*
Y514394D01*
X276805D01*
G01X272374Y504480D02*
X272219Y504250D01*
X272116Y503982D01*
Y503675D01*
X272271Y503330D01*
X272529Y503062D01*
X272839Y502870D01*
X273356Y502717D01*
X273821Y502679D01*
X274286Y502755D01*
X274596Y502870D01*
X274906Y503100D01*
X275113Y503369D01*
X275216Y503637D01*
Y503905D01*
X275113Y504174D01*
X274958Y504404D01*
X274751Y504595D01*
G01X272633Y506009D02*
X272323Y506239D01*
X272168Y506507D01*
X272116Y506814D01*
X272219Y507197D01*
X272478Y507465D01*
X272788Y507542D01*
X273098Y507504D01*
X273356Y507350D01*
X273873Y506584D01*
X274234Y506239D01*
X274751Y506009D01*
X275216Y505932D01*
Y507542D01*
G01Y509760D02*
X274544Y509837D01*
X273976Y509952D01*
X273459Y510105D01*
X272891Y510297D01*
X272116Y510604D01*
Y509070D01*
G01X272338Y514394D02*
Y520594D01*
X275538D01*
Y514394D01*
X272338D01*
G01X282048Y504123D02*
X281893Y503893D01*
X281790Y503625D01*
Y503318D01*
X281945Y502973D01*
X282203Y502705D01*
X282513Y502513D01*
X283030Y502360D01*
X283495Y502322D01*
X283960Y502398D01*
X284270Y502513D01*
X284580Y502743D01*
X284787Y503012D01*
X284890Y503280D01*
Y503548D01*
X284787Y503817D01*
X284632Y504047D01*
X284425Y504238D01*
G01X282307Y505652D02*
X281997Y505882D01*
X281842Y506150D01*
X281790Y506457D01*
X281893Y506840D01*
X282152Y507108D01*
X282462Y507185D01*
X282772Y507147D01*
X283030Y506993D01*
X283547Y506227D01*
X283908Y505882D01*
X284425Y505652D01*
X284890Y505575D01*
Y507185D01*
G01X284425Y508637D02*
X284683Y508867D01*
X284838Y509135D01*
X284890Y509480D01*
X284787Y509825D01*
X284580Y510093D01*
X284218Y510285D01*
X283805Y510323D01*
X283392Y510247D01*
X283133Y510055D01*
X282927Y509787D01*
X282875Y509518D01*
X282927Y509250D01*
X283133Y508905D01*
X281790Y509020D01*
Y510055D01*
G01X281176Y514394D02*
Y520594D01*
X284376D01*
Y514394D01*
X281176D01*
G01X267699Y504551D02*
X267544Y504321D01*
X267441Y504053D01*
Y503746D01*
X267596Y503401D01*
X267854Y503133D01*
X268164Y502941D01*
X268681Y502788D01*
X269146Y502750D01*
X269611Y502826D01*
X269921Y502941D01*
X270231Y503171D01*
X270438Y503440D01*
X270541Y503708D01*
Y503976D01*
X270438Y504245D01*
X270283Y504475D01*
X270076Y504666D01*
G01X267958Y506080D02*
X267648Y506310D01*
X267493Y506578D01*
X267441Y506885D01*
X267544Y507268D01*
X267803Y507536D01*
X268113Y507613D01*
X268423Y507575D01*
X268681Y507421D01*
X269198Y506655D01*
X269559Y506310D01*
X270076Y506080D01*
X270541Y506003D01*
Y507613D01*
G01Y509908D02*
X270489Y510176D01*
X270334Y510483D01*
X270076Y510675D01*
X269714Y510751D01*
X269353Y510675D01*
X269043Y510445D01*
X268888Y510100D01*
Y509716D01*
X268784Y509486D01*
X268526Y509295D01*
X268164Y509218D01*
X267803Y509333D01*
X267544Y509601D01*
X267441Y509908D01*
X267544Y510215D01*
X267803Y510483D01*
X268164Y510598D01*
X268526Y510521D01*
X268784Y510330D01*
X268888Y510100D01*
Y509716D01*
X269043Y509371D01*
X269353Y509141D01*
X269714Y509065D01*
X270076Y509141D01*
X270334Y509333D01*
X270489Y509640D01*
X270541Y509908D01*
G01X267916Y514394D02*
Y520594D01*
X271116D01*
Y514394D01*
X267916D01*
G01X279905Y517494D02*
X276905D01*
G01X275438D02*
X272438D01*
G01X284276D02*
X281276D01*
G01X271016D02*
X268016D01*
G01X289484Y587062D02*
X292484D01*
G01X292584Y590162D02*
Y583962D01*
X289384D01*
Y590162D01*
X292584D01*
G01X287648Y594162D02*
Y583962D01*
X283048D01*
Y594162D01*
X287648D01*
G01X289048Y599443D02*
X288893Y599213D01*
X288790Y598945D01*
Y598638D01*
X288945Y598293D01*
X289203Y598025D01*
X289513Y597833D01*
X290030Y597680D01*
X290495Y597642D01*
X290960Y597718D01*
X291270Y597833D01*
X291580Y598063D01*
X291787Y598332D01*
X291890Y598600D01*
Y598868D01*
X291787Y599137D01*
X291632Y599367D01*
X291425Y599558D01*
G01X289307Y600972D02*
X288997Y601202D01*
X288842Y601470D01*
X288790Y601777D01*
X288893Y602160D01*
X289152Y602428D01*
X289462Y602505D01*
X289772Y602467D01*
X290030Y602313D01*
X290547Y601547D01*
X290908Y601202D01*
X291425Y600972D01*
X291890Y600895D01*
Y602505D01*
G01X291270Y603957D02*
X291632Y604187D01*
X291838Y604493D01*
X291890Y604838D01*
X291838Y605145D01*
X291580Y605452D01*
X291270Y605643D01*
X290960Y605682D01*
X290598Y605605D01*
X290340Y605337D01*
X290237Y605068D01*
Y604723D01*
G01Y605068D02*
X290082Y605298D01*
X289823Y605490D01*
X289513Y605567D01*
X289203Y605490D01*
X288945Y605298D01*
X288790Y604953D01*
X288842Y604608D01*
X289048Y604263D01*
G01X284042Y599443D02*
X283887Y599213D01*
X283784Y598945D01*
Y598638D01*
X283939Y598293D01*
X284197Y598025D01*
X284507Y597833D01*
X285024Y597680D01*
X285489Y597642D01*
X285954Y597718D01*
X286264Y597833D01*
X286574Y598063D01*
X286781Y598332D01*
X286884Y598600D01*
Y598868D01*
X286781Y599137D01*
X286626Y599367D01*
X286419Y599558D01*
G01X284301Y600972D02*
X283991Y601202D01*
X283836Y601470D01*
X283784Y601777D01*
X283887Y602160D01*
X284146Y602428D01*
X284456Y602505D01*
X284766Y602467D01*
X285024Y602313D01*
X285541Y601547D01*
X285902Y601202D01*
X286419Y600972D01*
X286884Y600895D01*
Y602505D01*
G01X284301Y604072D02*
X283991Y604302D01*
X283836Y604570D01*
X283784Y604877D01*
X283887Y605260D01*
X284146Y605528D01*
X284456Y605605D01*
X284766Y605567D01*
X285024Y605413D01*
X285541Y604647D01*
X285902Y604302D01*
X286419Y604072D01*
X286884Y603995D01*
Y605605D01*
G01X287648Y589062D02*
X283048D01*
G01X283401Y678335D02*
X283246Y678105D01*
X283143Y677837D01*
Y677530D01*
X283298Y677185D01*
X283556Y676917D01*
X283866Y676725D01*
X284383Y676572D01*
X284848Y676534D01*
X285313Y676610D01*
X285623Y676725D01*
X285933Y676955D01*
X286140Y677224D01*
X286243Y677492D01*
Y677760D01*
X286140Y678029D01*
X285985Y678259D01*
X285778Y678450D01*
G01X285623Y679749D02*
X285985Y679979D01*
X286191Y680285D01*
X286243Y680630D01*
X286191Y680937D01*
X285933Y681244D01*
X285623Y681435D01*
X285313Y681474D01*
X284951Y681397D01*
X284693Y681129D01*
X284590Y680860D01*
Y680515D01*
G01Y680860D02*
X284435Y681090D01*
X284176Y681282D01*
X283866Y681359D01*
X283556Y681282D01*
X283298Y681090D01*
X283143Y680745D01*
X283195Y680400D01*
X283401Y680055D01*
G01X283660Y682964D02*
X283350Y683194D01*
X283195Y683462D01*
X283143Y683769D01*
X283246Y684152D01*
X283505Y684420D01*
X283815Y684497D01*
X284125Y684459D01*
X284383Y684305D01*
X284900Y683539D01*
X285261Y683194D01*
X285778Y682964D01*
X286243Y682887D01*
Y684497D01*
G01X278280Y678336D02*
X278125Y678106D01*
X278022Y677838D01*
Y677531D01*
X278177Y677186D01*
X278435Y676918D01*
X278745Y676726D01*
X279262Y676573D01*
X279727Y676535D01*
X280192Y676611D01*
X280502Y676726D01*
X280812Y676956D01*
X281019Y677225D01*
X281122Y677493D01*
Y677761D01*
X281019Y678030D01*
X280864Y678260D01*
X280657Y678451D01*
G01X280502Y679750D02*
X280864Y679980D01*
X281070Y680286D01*
X281122Y680631D01*
X281070Y680938D01*
X280812Y681245D01*
X280502Y681436D01*
X280192Y681475D01*
X279830Y681398D01*
X279572Y681130D01*
X279469Y680861D01*
Y680516D01*
G01Y680861D02*
X279314Y681091D01*
X279055Y681283D01*
X278745Y681360D01*
X278435Y681283D01*
X278177Y681091D01*
X278022Y680746D01*
X278074Y680401D01*
X278280Y680056D01*
G01X280502Y682850D02*
X280864Y683080D01*
X281070Y683386D01*
X281122Y683731D01*
X281070Y684038D01*
X280812Y684345D01*
X280502Y684536D01*
X280192Y684575D01*
X279830Y684498D01*
X279572Y684230D01*
X279469Y683961D01*
Y683616D01*
G01Y683961D02*
X279314Y684191D01*
X279055Y684383D01*
X278745Y684460D01*
X278435Y684383D01*
X278177Y684191D01*
X278022Y683846D01*
X278074Y683501D01*
X278280Y683156D01*
G01X273622Y678621D02*
X273467Y678391D01*
X273364Y678123D01*
Y677816D01*
X273519Y677471D01*
X273777Y677203D01*
X274087Y677011D01*
X274604Y676858D01*
X275069Y676820D01*
X275534Y676896D01*
X275844Y677011D01*
X276154Y677241D01*
X276361Y677510D01*
X276464Y677778D01*
Y678046D01*
X276361Y678315D01*
X276206Y678545D01*
X275999Y678736D01*
G01X275844Y680035D02*
X276206Y680265D01*
X276412Y680571D01*
X276464Y680916D01*
X276412Y681223D01*
X276154Y681530D01*
X275844Y681721D01*
X275534Y681760D01*
X275172Y681683D01*
X274914Y681415D01*
X274811Y681146D01*
Y680801D01*
G01Y681146D02*
X274656Y681376D01*
X274397Y681568D01*
X274087Y681645D01*
X273777Y681568D01*
X273519Y681376D01*
X273364Y681031D01*
X273416Y680686D01*
X273622Y680341D01*
G01X276464Y684438D02*
X273364D01*
X275586Y683020D01*
Y684936D01*
G01X268901Y678621D02*
X268746Y678391D01*
X268643Y678123D01*
Y677816D01*
X268798Y677471D01*
X269056Y677203D01*
X269366Y677011D01*
X269883Y676858D01*
X270348Y676820D01*
X270813Y676896D01*
X271123Y677011D01*
X271433Y677241D01*
X271640Y677510D01*
X271743Y677778D01*
Y678046D01*
X271640Y678315D01*
X271485Y678545D01*
X271278Y678736D01*
G01X271123Y680035D02*
X271485Y680265D01*
X271691Y680571D01*
X271743Y680916D01*
X271691Y681223D01*
X271433Y681530D01*
X271123Y681721D01*
X270813Y681760D01*
X270451Y681683D01*
X270193Y681415D01*
X270090Y681146D01*
Y680801D01*
G01Y681146D02*
X269935Y681376D01*
X269676Y681568D01*
X269366Y681645D01*
X269056Y681568D01*
X268798Y681376D01*
X268643Y681031D01*
X268695Y680686D01*
X268901Y680341D01*
G01X271278Y683135D02*
X271536Y683365D01*
X271691Y683633D01*
X271743Y683978D01*
X271640Y684323D01*
X271433Y684591D01*
X271071Y684783D01*
X270658Y684821D01*
X270245Y684745D01*
X269986Y684553D01*
X269780Y684285D01*
X269728Y684016D01*
X269780Y683748D01*
X269986Y683403D01*
X268643Y683518D01*
Y684553D01*
G01X284840Y692699D02*
X281840D01*
G01X281740Y689599D02*
Y695799D01*
X284940D01*
Y689599D01*
X281740D01*
G01X280455Y692699D02*
X277455D01*
G01X277355Y689599D02*
Y695799D01*
X280555D01*
Y689599D01*
X277355D01*
G01X276014Y692699D02*
X273014D01*
G01X272914Y689599D02*
Y695799D01*
X276114D01*
Y689599D01*
X272914D01*
G01X271609Y692699D02*
X268609D01*
G01X268509Y689599D02*
Y695799D01*
X271709D01*
Y689599D01*
X268509D01*
G01X276684Y762136D02*
X279684D01*
G01X279784Y765236D02*
Y759036D01*
X276584D01*
Y765236D01*
X279784D01*
G01X281237Y762136D02*
X284237D01*
G01X284337Y765236D02*
Y759036D01*
X281137D01*
Y765236D01*
X284337D01*
G01X288062Y760276D02*
X287907Y760046D01*
X287804Y759778D01*
Y759471D01*
X287959Y759126D01*
X288217Y758858D01*
X288527Y758666D01*
X289044Y758513D01*
X289509Y758475D01*
X289974Y758551D01*
X290284Y758666D01*
X290594Y758896D01*
X290801Y759165D01*
X290904Y759433D01*
Y759701D01*
X290801Y759970D01*
X290646Y760200D01*
X290439Y760391D01*
G01X288321Y761805D02*
X288011Y762035D01*
X287856Y762303D01*
X287804Y762610D01*
X287907Y762993D01*
X288166Y763261D01*
X288476Y763338D01*
X288786Y763300D01*
X289044Y763146D01*
X289561Y762380D01*
X289922Y762035D01*
X290439Y761805D01*
X290904Y761728D01*
Y763338D01*
G01X290542Y764981D02*
X290801Y765250D01*
X290904Y765556D01*
X290801Y765863D01*
X290491Y766131D01*
X290026Y766323D01*
X289561Y766400D01*
X288992D01*
X288527Y766323D01*
X288114Y766131D01*
X287907Y765901D01*
X287804Y765633D01*
X287907Y765326D01*
X288114Y765096D01*
X288424Y764943D01*
X288837Y764866D01*
X289199Y764943D01*
X289561Y765135D01*
X289767Y765365D01*
X289819Y765633D01*
X289716Y765940D01*
X289457Y766170D01*
X288992Y766400D01*
G01X275414Y769236D02*
Y759036D01*
X270814D01*
Y769236D01*
X275414D01*
G01Y764136D02*
X270814D01*
G01X338582Y827165D02*
G03I-31496J0D01*
G01X284466Y854277D02*
X284311Y854047D01*
X284208Y853779D01*
Y853472D01*
X284363Y853127D01*
X284621Y852859D01*
X284931Y852667D01*
X285448Y852514D01*
X285913Y852476D01*
X286378Y852552D01*
X286688Y852667D01*
X286998Y852897D01*
X287205Y853166D01*
X287308Y853434D01*
Y853702D01*
X287205Y853971D01*
X287050Y854201D01*
X286843Y854392D01*
G01X286688Y855691D02*
X287050Y855921D01*
X287256Y856227D01*
X287308Y856572D01*
X287256Y856879D01*
X286998Y857186D01*
X286688Y857377D01*
X286378Y857416D01*
X286016Y857339D01*
X285758Y857071D01*
X285655Y856802D01*
Y856457D01*
G01Y856802D02*
X285500Y857032D01*
X285241Y857224D01*
X284931Y857301D01*
X284621Y857224D01*
X284363Y857032D01*
X284208Y856687D01*
X284260Y856342D01*
X284466Y855997D01*
G01X286946Y858982D02*
X287205Y859251D01*
X287308Y859557D01*
X287205Y859864D01*
X286895Y860132D01*
X286430Y860324D01*
X285965Y860401D01*
X285396D01*
X284931Y860324D01*
X284518Y860132D01*
X284311Y859902D01*
X284208Y859634D01*
X284311Y859327D01*
X284518Y859097D01*
X284828Y858944D01*
X285241Y858867D01*
X285603Y858944D01*
X285965Y859136D01*
X286171Y859366D01*
X286223Y859634D01*
X286120Y859941D01*
X285861Y860171D01*
X285396Y860401D01*
G01X279417Y854419D02*
X279262Y854189D01*
X279159Y853921D01*
Y853614D01*
X279314Y853269D01*
X279572Y853001D01*
X279882Y852809D01*
X280399Y852656D01*
X280864Y852618D01*
X281329Y852694D01*
X281639Y852809D01*
X281949Y853039D01*
X282156Y853308D01*
X282259Y853576D01*
Y853844D01*
X282156Y854113D01*
X282001Y854343D01*
X281794Y854534D01*
G01X282259Y857136D02*
X279159D01*
X281381Y855718D01*
Y857634D01*
G01X279159Y859776D02*
X279262Y859469D01*
X279521Y859239D01*
X279831Y859086D01*
X280244Y858971D01*
X280709Y858933D01*
X281174Y858971D01*
X281587Y859086D01*
X281897Y859239D01*
X282156Y859469D01*
X282259Y859776D01*
X282156Y860083D01*
X281897Y860313D01*
X281587Y860466D01*
X281174Y860581D01*
X280709Y860619D01*
X280244Y860581D01*
X279831Y860466D01*
X279521Y860313D01*
X279262Y860083D01*
X279159Y859776D01*
G01X274415Y854419D02*
X274260Y854189D01*
X274157Y853921D01*
Y853614D01*
X274312Y853269D01*
X274570Y853001D01*
X274880Y852809D01*
X275397Y852656D01*
X275862Y852618D01*
X276327Y852694D01*
X276637Y852809D01*
X276947Y853039D01*
X277154Y853308D01*
X277257Y853576D01*
Y853844D01*
X277154Y854113D01*
X276999Y854343D01*
X276792Y854534D01*
G01X277257Y857136D02*
X274157D01*
X276379Y855718D01*
Y857634D01*
G01X277257Y859776D02*
X274157D01*
X274777Y859316D01*
G01X277257D02*
Y860236D01*
G01X269585Y854490D02*
X269430Y854260D01*
X269327Y853992D01*
Y853685D01*
X269482Y853340D01*
X269740Y853072D01*
X270050Y852880D01*
X270567Y852727D01*
X271032Y852689D01*
X271497Y852765D01*
X271807Y852880D01*
X272117Y853110D01*
X272324Y853379D01*
X272427Y853647D01*
Y853915D01*
X272324Y854184D01*
X272169Y854414D01*
X271962Y854605D01*
G01X272427Y857207D02*
X269327D01*
X271549Y855789D01*
Y857705D01*
G01X269844Y859119D02*
X269534Y859349D01*
X269379Y859617D01*
X269327Y859924D01*
X269430Y860307D01*
X269689Y860575D01*
X269999Y860652D01*
X270309Y860614D01*
X270567Y860460D01*
X271084Y859694D01*
X271445Y859349D01*
X271962Y859119D01*
X272427Y859042D01*
Y860652D01*
G01X287288Y867818D02*
X284288D01*
G01X284188Y864718D02*
Y870918D01*
X287388D01*
Y864718D01*
X284188D01*
G01X282805Y867818D02*
X279805D01*
G01X279705Y864718D02*
Y870918D01*
X282905D01*
Y864718D01*
X279705D01*
G01X278186Y867818D02*
X275186D01*
G01X275086Y864718D02*
Y870918D01*
X278286D01*
Y864718D01*
X275086D01*
G01X273681Y867818D02*
X270681D01*
G01X270581Y864718D02*
Y870918D01*
X273781D01*
Y864718D01*
X270581D01*
G01X279694Y935861D02*
X282694D01*
G01X282794Y938961D02*
Y932761D01*
X279594D01*
Y938961D01*
X282794D01*
G01X284374Y935861D02*
X287374D01*
G01X287474Y938961D02*
Y932761D01*
X284274D01*
Y938961D01*
X287474D01*
G01X289394Y934964D02*
X289239Y934734D01*
X289136Y934466D01*
Y934159D01*
X289291Y933814D01*
X289549Y933546D01*
X289859Y933354D01*
X290376Y933201D01*
X290841Y933163D01*
X291306Y933239D01*
X291616Y933354D01*
X291926Y933584D01*
X292133Y933853D01*
X292236Y934121D01*
Y934389D01*
X292133Y934658D01*
X291978Y934888D01*
X291771Y935079D01*
G01X291616Y936378D02*
X291978Y936608D01*
X292184Y936914D01*
X292236Y937259D01*
X292184Y937566D01*
X291926Y937873D01*
X291616Y938064D01*
X291306Y938103D01*
X290944Y938026D01*
X290686Y937758D01*
X290583Y937489D01*
Y937144D01*
G01Y937489D02*
X290428Y937719D01*
X290169Y937911D01*
X289859Y937988D01*
X289549Y937911D01*
X289291Y937719D01*
X289136Y937374D01*
X289188Y937029D01*
X289394Y936684D01*
G01X290944Y939593D02*
X290583Y939861D01*
X290376Y940091D01*
X290273Y940398D01*
X290376Y940666D01*
X290583Y940858D01*
X290893Y941011D01*
X291254Y941049D01*
X291564Y941011D01*
X291874Y940858D01*
X292133Y940628D01*
X292236Y940359D01*
X292133Y940053D01*
X291823Y939784D01*
X291358Y939631D01*
X290841Y939593D01*
X290169Y939669D01*
X289808Y939784D01*
X289446Y939976D01*
X289188Y940244D01*
X289136Y940513D01*
X289239Y940781D01*
X289498Y940973D01*
G01X278266Y942961D02*
Y932761D01*
X273666D01*
Y942961D01*
X278266D01*
G01Y937861D02*
X273666D01*
G01X289085Y1021229D02*
X288930Y1020999D01*
X288827Y1020731D01*
Y1020424D01*
X288982Y1020079D01*
X289240Y1019811D01*
X289550Y1019619D01*
X290067Y1019466D01*
X290532Y1019428D01*
X290997Y1019504D01*
X291307Y1019619D01*
X291617Y1019849D01*
X291824Y1020118D01*
X291927Y1020386D01*
Y1020654D01*
X291824Y1020923D01*
X291669Y1021153D01*
X291462Y1021344D01*
G01X291927Y1023946D02*
X288827D01*
X291049Y1022528D01*
Y1024444D01*
G01X291927Y1026509D02*
X291255Y1026586D01*
X290687Y1026701D01*
X290170Y1026854D01*
X289602Y1027046D01*
X288827Y1027353D01*
Y1025819D01*
G01X284036Y1021229D02*
X283881Y1020999D01*
X283778Y1020731D01*
Y1020424D01*
X283933Y1020079D01*
X284191Y1019811D01*
X284501Y1019619D01*
X285018Y1019466D01*
X285483Y1019428D01*
X285948Y1019504D01*
X286258Y1019619D01*
X286568Y1019849D01*
X286775Y1020118D01*
X286878Y1020386D01*
Y1020654D01*
X286775Y1020923D01*
X286620Y1021153D01*
X286413Y1021344D01*
G01X286878Y1023946D02*
X283778D01*
X286000Y1022528D01*
Y1024444D01*
G01X286878Y1026586D02*
X286826Y1026854D01*
X286671Y1027161D01*
X286413Y1027353D01*
X286051Y1027429D01*
X285690Y1027353D01*
X285380Y1027123D01*
X285225Y1026778D01*
Y1026394D01*
X285121Y1026164D01*
X284863Y1025973D01*
X284501Y1025896D01*
X284140Y1026011D01*
X283881Y1026279D01*
X283778Y1026586D01*
X283881Y1026893D01*
X284140Y1027161D01*
X284501Y1027276D01*
X284863Y1027199D01*
X285121Y1027008D01*
X285225Y1026778D01*
Y1026394D01*
X285380Y1026049D01*
X285690Y1025819D01*
X286051Y1025743D01*
X286413Y1025819D01*
X286671Y1026011D01*
X286826Y1026318D01*
X286878Y1026586D01*
G01X279174Y1021301D02*
X279019Y1021071D01*
X278916Y1020803D01*
Y1020496D01*
X279071Y1020151D01*
X279329Y1019883D01*
X279639Y1019691D01*
X280156Y1019538D01*
X280621Y1019500D01*
X281086Y1019576D01*
X281396Y1019691D01*
X281706Y1019921D01*
X281913Y1020190D01*
X282016Y1020458D01*
Y1020726D01*
X281913Y1020995D01*
X281758Y1021225D01*
X281551Y1021416D01*
G01X282016Y1024018D02*
X278916D01*
X281138Y1022600D01*
Y1024516D01*
G01X281654Y1026006D02*
X281913Y1026275D01*
X282016Y1026581D01*
X281913Y1026888D01*
X281603Y1027156D01*
X281138Y1027348D01*
X280673Y1027425D01*
X280104D01*
X279639Y1027348D01*
X279226Y1027156D01*
X279019Y1026926D01*
X278916Y1026658D01*
X279019Y1026351D01*
X279226Y1026121D01*
X279536Y1025968D01*
X279949Y1025891D01*
X280311Y1025968D01*
X280673Y1026160D01*
X280879Y1026390D01*
X280931Y1026658D01*
X280828Y1026965D01*
X280569Y1027195D01*
X280104Y1027425D01*
G01X291607Y1036457D02*
X288607D01*
G01X288507Y1033357D02*
Y1039557D01*
X291707D01*
Y1033357D01*
X288507D01*
G01X287166Y1036457D02*
X284166D01*
G01X284066Y1033357D02*
Y1039557D01*
X287266D01*
Y1033357D01*
X284066D01*
G01X282624Y1036457D02*
X279624D01*
G01X279524Y1033357D02*
Y1039557D01*
X282724D01*
Y1033357D01*
X279524D01*
G01X286688Y1110851D02*
X289688D01*
G01X289788Y1113951D02*
Y1107751D01*
X286588D01*
Y1113951D01*
X289788D01*
G01X285258Y1117951D02*
Y1107751D01*
X280658D01*
Y1117951D01*
X285258D01*
G01Y1112851D02*
X280658D01*
G01X285694Y1211889D02*
X282694D01*
G01X282594Y1208789D02*
Y1214989D01*
X285794D01*
Y1208789D01*
X282594D01*
G01X290582Y1211889D02*
X287582D01*
G01X287482Y1208789D02*
Y1214989D01*
X290682D01*
Y1208789D01*
X287482D01*
G01X281059Y1211889D02*
X278059D01*
G01X277959Y1208789D02*
Y1214989D01*
X281159D01*
Y1208789D01*
X277959D01*
G01X287710Y1285522D02*
X290710D01*
G01X290810Y1288622D02*
Y1282422D01*
X287610D01*
Y1288622D01*
X290810D01*
G01X286108Y1292622D02*
Y1282422D01*
X281508D01*
Y1292622D01*
X286108D01*
G01Y1287522D02*
X281508D01*
G01X287596Y1298351D02*
X287441Y1298121D01*
X287338Y1297853D01*
Y1297546D01*
X287493Y1297201D01*
X287751Y1296933D01*
X288061Y1296741D01*
X288578Y1296588D01*
X289043Y1296550D01*
X289508Y1296626D01*
X289818Y1296741D01*
X290128Y1296971D01*
X290335Y1297240D01*
X290438Y1297508D01*
Y1297776D01*
X290335Y1298045D01*
X290180Y1298275D01*
X289973Y1298466D01*
G01Y1299765D02*
X290231Y1299995D01*
X290386Y1300263D01*
X290438Y1300608D01*
X290335Y1300953D01*
X290128Y1301221D01*
X289766Y1301413D01*
X289353Y1301451D01*
X288940Y1301375D01*
X288681Y1301183D01*
X288475Y1300915D01*
X288423Y1300646D01*
X288475Y1300378D01*
X288681Y1300033D01*
X287338Y1300148D01*
Y1301183D01*
G01X290438Y1303708D02*
X287338D01*
X287958Y1303248D01*
G01X290438D02*
Y1304168D01*
G01X282480Y1298351D02*
X282325Y1298121D01*
X282222Y1297853D01*
Y1297546D01*
X282377Y1297201D01*
X282635Y1296933D01*
X282945Y1296741D01*
X283462Y1296588D01*
X283927Y1296550D01*
X284392Y1296626D01*
X284702Y1296741D01*
X285012Y1296971D01*
X285219Y1297240D01*
X285322Y1297508D01*
Y1297776D01*
X285219Y1298045D01*
X285064Y1298275D01*
X284857Y1298466D01*
G01Y1299765D02*
X285115Y1299995D01*
X285270Y1300263D01*
X285322Y1300608D01*
X285219Y1300953D01*
X285012Y1301221D01*
X284650Y1301413D01*
X284237Y1301451D01*
X283824Y1301375D01*
X283565Y1301183D01*
X283359Y1300915D01*
X283307Y1300646D01*
X283359Y1300378D01*
X283565Y1300033D01*
X282222Y1300148D01*
Y1301183D01*
G01Y1303708D02*
X282325Y1303401D01*
X282584Y1303171D01*
X282894Y1303018D01*
X283307Y1302903D01*
X283772Y1302865D01*
X284237Y1302903D01*
X284650Y1303018D01*
X284960Y1303171D01*
X285219Y1303401D01*
X285322Y1303708D01*
X285219Y1304015D01*
X284960Y1304245D01*
X284650Y1304398D01*
X284237Y1304513D01*
X283772Y1304551D01*
X283307Y1304513D01*
X282894Y1304398D01*
X282584Y1304245D01*
X282325Y1304015D01*
X282222Y1303708D01*
G01X338582Y1343504D02*
G03I-31496J0D01*
G01X285863Y1381452D02*
X285708Y1381222D01*
X285605Y1380954D01*
Y1380647D01*
X285760Y1380302D01*
X286018Y1380034D01*
X286328Y1379842D01*
X286845Y1379689D01*
X287310Y1379651D01*
X287775Y1379727D01*
X288085Y1379842D01*
X288395Y1380072D01*
X288602Y1380341D01*
X288705Y1380609D01*
Y1380877D01*
X288602Y1381146D01*
X288447Y1381376D01*
X288240Y1381567D01*
G01X287413Y1382981D02*
X287052Y1383249D01*
X286845Y1383479D01*
X286742Y1383786D01*
X286845Y1384054D01*
X287052Y1384246D01*
X287362Y1384399D01*
X287723Y1384437D01*
X288033Y1384399D01*
X288343Y1384246D01*
X288602Y1384016D01*
X288705Y1383747D01*
X288602Y1383441D01*
X288292Y1383172D01*
X287827Y1383019D01*
X287310Y1382981D01*
X286638Y1383057D01*
X286277Y1383172D01*
X285915Y1383364D01*
X285657Y1383632D01*
X285605Y1383901D01*
X285708Y1384169D01*
X285967Y1384361D01*
G01X285605Y1386809D02*
X285708Y1386502D01*
X285967Y1386272D01*
X286277Y1386119D01*
X286690Y1386004D01*
X287155Y1385966D01*
X287620Y1386004D01*
X288033Y1386119D01*
X288343Y1386272D01*
X288602Y1386502D01*
X288705Y1386809D01*
X288602Y1387116D01*
X288343Y1387346D01*
X288033Y1387499D01*
X287620Y1387614D01*
X287155Y1387652D01*
X286690Y1387614D01*
X286277Y1387499D01*
X285967Y1387346D01*
X285708Y1387116D01*
X285605Y1386809D01*
G01X280471Y1381524D02*
X280316Y1381294D01*
X280213Y1381026D01*
Y1380719D01*
X280368Y1380374D01*
X280626Y1380106D01*
X280936Y1379914D01*
X281453Y1379761D01*
X281918Y1379723D01*
X282383Y1379799D01*
X282693Y1379914D01*
X283003Y1380144D01*
X283210Y1380413D01*
X283313Y1380681D01*
Y1380949D01*
X283210Y1381218D01*
X283055Y1381448D01*
X282848Y1381639D01*
G01X282021Y1383053D02*
X281660Y1383321D01*
X281453Y1383551D01*
X281350Y1383858D01*
X281453Y1384126D01*
X281660Y1384318D01*
X281970Y1384471D01*
X282331Y1384509D01*
X282641Y1384471D01*
X282951Y1384318D01*
X283210Y1384088D01*
X283313Y1383819D01*
X283210Y1383513D01*
X282900Y1383244D01*
X282435Y1383091D01*
X281918Y1383053D01*
X281246Y1383129D01*
X280885Y1383244D01*
X280523Y1383436D01*
X280265Y1383704D01*
X280213Y1383973D01*
X280316Y1384241D01*
X280575Y1384433D01*
G01X283313Y1386881D02*
X280213D01*
X280833Y1386421D01*
G01X283313D02*
Y1387341D01*
G01X274978Y1381452D02*
X274823Y1381222D01*
X274720Y1380954D01*
Y1380647D01*
X274875Y1380302D01*
X275133Y1380034D01*
X275443Y1379842D01*
X275960Y1379689D01*
X276425Y1379651D01*
X276890Y1379727D01*
X277200Y1379842D01*
X277510Y1380072D01*
X277717Y1380341D01*
X277820Y1380609D01*
Y1380877D01*
X277717Y1381146D01*
X277562Y1381376D01*
X277355Y1381567D01*
G01X276528Y1382981D02*
X276167Y1383249D01*
X275960Y1383479D01*
X275857Y1383786D01*
X275960Y1384054D01*
X276167Y1384246D01*
X276477Y1384399D01*
X276838Y1384437D01*
X277148Y1384399D01*
X277458Y1384246D01*
X277717Y1384016D01*
X277820Y1383747D01*
X277717Y1383441D01*
X277407Y1383172D01*
X276942Y1383019D01*
X276425Y1382981D01*
X275753Y1383057D01*
X275392Y1383172D01*
X275030Y1383364D01*
X274772Y1383632D01*
X274720Y1383901D01*
X274823Y1384169D01*
X275082Y1384361D01*
G01X275237Y1386081D02*
X274927Y1386311D01*
X274772Y1386579D01*
X274720Y1386886D01*
X274823Y1387269D01*
X275082Y1387537D01*
X275392Y1387614D01*
X275702Y1387576D01*
X275960Y1387422D01*
X276477Y1386656D01*
X276838Y1386311D01*
X277355Y1386081D01*
X277820Y1386004D01*
Y1387614D01*
G01X269485Y1381596D02*
X269330Y1381366D01*
X269227Y1381098D01*
Y1380791D01*
X269382Y1380446D01*
X269640Y1380178D01*
X269950Y1379986D01*
X270467Y1379833D01*
X270932Y1379795D01*
X271397Y1379871D01*
X271707Y1379986D01*
X272017Y1380216D01*
X272224Y1380485D01*
X272327Y1380753D01*
Y1381021D01*
X272224Y1381290D01*
X272069Y1381520D01*
X271862Y1381711D01*
G01X271035Y1383125D02*
X270674Y1383393D01*
X270467Y1383623D01*
X270364Y1383930D01*
X270467Y1384198D01*
X270674Y1384390D01*
X270984Y1384543D01*
X271345Y1384581D01*
X271655Y1384543D01*
X271965Y1384390D01*
X272224Y1384160D01*
X272327Y1383891D01*
X272224Y1383585D01*
X271914Y1383316D01*
X271449Y1383163D01*
X270932Y1383125D01*
X270260Y1383201D01*
X269899Y1383316D01*
X269537Y1383508D01*
X269279Y1383776D01*
X269227Y1384045D01*
X269330Y1384313D01*
X269589Y1384505D01*
G01X271707Y1386110D02*
X272069Y1386340D01*
X272275Y1386646D01*
X272327Y1386991D01*
X272275Y1387298D01*
X272017Y1387605D01*
X271707Y1387796D01*
X271397Y1387835D01*
X271035Y1387758D01*
X270777Y1387490D01*
X270674Y1387221D01*
Y1386876D01*
G01Y1387221D02*
X270519Y1387451D01*
X270260Y1387643D01*
X269950Y1387720D01*
X269640Y1387643D01*
X269382Y1387451D01*
X269227Y1387106D01*
X269279Y1386761D01*
X269485Y1386416D01*
G01X282031Y1370171D02*
Y1373271D01*
G01X283641D02*
Y1370171D01*
G01Y1371721D02*
X282031D01*
G01X285093Y1370636D02*
X285323Y1370378D01*
X285591Y1370223D01*
X285936Y1370171D01*
X286281Y1370274D01*
X286549Y1370481D01*
X286741Y1370843D01*
X286779Y1371256D01*
X286703Y1371669D01*
X286511Y1371928D01*
X286243Y1372134D01*
X285974Y1372186D01*
X285706Y1372134D01*
X285361Y1371928D01*
X285476Y1373271D01*
X286511D01*
G01X285740Y1394917D02*
X282740D01*
G01X282640Y1391817D02*
Y1398017D01*
X285840D01*
Y1391817D01*
X282640D01*
G01X281018Y1394916D02*
X278018D01*
G01X277918Y1391816D02*
Y1398016D01*
X281118D01*
Y1391816D01*
X277918D01*
G01X276552Y1394916D02*
X273552D01*
G01X273452Y1391816D02*
Y1398016D01*
X276652D01*
Y1391816D01*
X273452D01*
G01X272079Y1394916D02*
X269079D01*
G01X268979Y1391816D02*
Y1398016D01*
X272179D01*
Y1391816D01*
X268979D01*
G01X277121Y1462162D02*
Y1455962D01*
X273921D01*
Y1462162D01*
X277121D01*
G01X281590D02*
Y1455962D01*
X278390D01*
Y1462162D01*
X281590D01*
G01X272534Y1466162D02*
Y1455962D01*
X267934D01*
Y1466162D01*
X272534D01*
G01X273488Y1471587D02*
X273333Y1471357D01*
X273230Y1471089D01*
Y1470782D01*
X273385Y1470437D01*
X273643Y1470169D01*
X273953Y1469977D01*
X274470Y1469824D01*
X274935Y1469786D01*
X275400Y1469862D01*
X275710Y1469977D01*
X276020Y1470207D01*
X276227Y1470476D01*
X276330Y1470744D01*
Y1471012D01*
X276227Y1471281D01*
X276072Y1471511D01*
X275865Y1471702D01*
G01Y1473001D02*
X276123Y1473231D01*
X276278Y1473499D01*
X276330Y1473844D01*
X276227Y1474189D01*
X276020Y1474457D01*
X275658Y1474649D01*
X275245Y1474687D01*
X274832Y1474611D01*
X274573Y1474419D01*
X274367Y1474151D01*
X274315Y1473882D01*
X274367Y1473614D01*
X274573Y1473269D01*
X273230Y1473384D01*
Y1474419D01*
G01X276330Y1476944D02*
X276278Y1477212D01*
X276123Y1477519D01*
X275865Y1477711D01*
X275503Y1477787D01*
X275142Y1477711D01*
X274832Y1477481D01*
X274677Y1477136D01*
Y1476752D01*
X274573Y1476522D01*
X274315Y1476331D01*
X273953Y1476254D01*
X273592Y1476369D01*
X273333Y1476637D01*
X273230Y1476944D01*
X273333Y1477251D01*
X273592Y1477519D01*
X273953Y1477634D01*
X274315Y1477557D01*
X274573Y1477366D01*
X274677Y1477136D01*
Y1476752D01*
X274832Y1476407D01*
X275142Y1476177D01*
X275503Y1476101D01*
X275865Y1476177D01*
X276123Y1476369D01*
X276278Y1476676D01*
X276330Y1476944D01*
G01X274021Y1459062D02*
X277021D01*
G01X279007Y1471587D02*
X278852Y1471357D01*
X278749Y1471089D01*
Y1470782D01*
X278904Y1470437D01*
X279162Y1470169D01*
X279472Y1469977D01*
X279989Y1469824D01*
X280454Y1469786D01*
X280919Y1469862D01*
X281229Y1469977D01*
X281539Y1470207D01*
X281746Y1470476D01*
X281849Y1470744D01*
Y1471012D01*
X281746Y1471281D01*
X281591Y1471511D01*
X281384Y1471702D01*
G01Y1473001D02*
X281642Y1473231D01*
X281797Y1473499D01*
X281849Y1473844D01*
X281746Y1474189D01*
X281539Y1474457D01*
X281177Y1474649D01*
X280764Y1474687D01*
X280351Y1474611D01*
X280092Y1474419D01*
X279886Y1474151D01*
X279834Y1473882D01*
X279886Y1473614D01*
X280092Y1473269D01*
X278749Y1473384D01*
Y1474419D01*
G01X281487Y1476292D02*
X281746Y1476561D01*
X281849Y1476867D01*
X281746Y1477174D01*
X281436Y1477442D01*
X280971Y1477634D01*
X280506Y1477711D01*
X279937D01*
X279472Y1477634D01*
X279059Y1477442D01*
X278852Y1477212D01*
X278749Y1476944D01*
X278852Y1476637D01*
X279059Y1476407D01*
X279369Y1476254D01*
X279782Y1476177D01*
X280144Y1476254D01*
X280506Y1476446D01*
X280712Y1476676D01*
X280764Y1476944D01*
X280661Y1477251D01*
X280402Y1477481D01*
X279937Y1477711D01*
G01X278490Y1459062D02*
X281490D01*
G01X268169Y1471587D02*
X268014Y1471357D01*
X267911Y1471089D01*
Y1470782D01*
X268066Y1470437D01*
X268324Y1470169D01*
X268634Y1469977D01*
X269151Y1469824D01*
X269616Y1469786D01*
X270081Y1469862D01*
X270391Y1469977D01*
X270701Y1470207D01*
X270908Y1470476D01*
X271011Y1470744D01*
Y1471012D01*
X270908Y1471281D01*
X270753Y1471511D01*
X270546Y1471702D01*
G01Y1473001D02*
X270804Y1473231D01*
X270959Y1473499D01*
X271011Y1473844D01*
X270908Y1474189D01*
X270701Y1474457D01*
X270339Y1474649D01*
X269926Y1474687D01*
X269513Y1474611D01*
X269254Y1474419D01*
X269048Y1474151D01*
X268996Y1473882D01*
X269048Y1473614D01*
X269254Y1473269D01*
X267911Y1473384D01*
Y1474419D01*
G01X271011Y1476867D02*
X270339Y1476944D01*
X269771Y1477059D01*
X269254Y1477212D01*
X268686Y1477404D01*
X267911Y1477711D01*
Y1476177D01*
G01X272534Y1461062D02*
X267934D01*
G01X279095Y1559474D02*
X278940Y1559244D01*
X278837Y1558976D01*
Y1558669D01*
X278992Y1558324D01*
X279250Y1558056D01*
X279560Y1557864D01*
X280077Y1557711D01*
X280542Y1557673D01*
X281007Y1557749D01*
X281317Y1557864D01*
X281627Y1558094D01*
X281834Y1558363D01*
X281937Y1558631D01*
Y1558899D01*
X281834Y1559168D01*
X281679Y1559398D01*
X281472Y1559589D01*
G01X280645Y1561003D02*
X280284Y1561271D01*
X280077Y1561501D01*
X279974Y1561808D01*
X280077Y1562076D01*
X280284Y1562268D01*
X280594Y1562421D01*
X280955Y1562459D01*
X281265Y1562421D01*
X281575Y1562268D01*
X281834Y1562038D01*
X281937Y1561769D01*
X281834Y1561463D01*
X281524Y1561194D01*
X281059Y1561041D01*
X280542Y1561003D01*
X279870Y1561079D01*
X279509Y1561194D01*
X279147Y1561386D01*
X278889Y1561654D01*
X278837Y1561923D01*
X278940Y1562191D01*
X279199Y1562383D01*
G01X281937Y1564754D02*
X281265Y1564831D01*
X280697Y1564946D01*
X280180Y1565099D01*
X279612Y1565291D01*
X278837Y1565598D01*
Y1564064D01*
G01X268855Y1559475D02*
X268700Y1559245D01*
X268597Y1558977D01*
Y1558670D01*
X268752Y1558325D01*
X269010Y1558057D01*
X269320Y1557865D01*
X269837Y1557712D01*
X270302Y1557674D01*
X270767Y1557750D01*
X271077Y1557865D01*
X271387Y1558095D01*
X271594Y1558364D01*
X271697Y1558632D01*
Y1558900D01*
X271594Y1559169D01*
X271439Y1559399D01*
X271232Y1559590D01*
G01X270405Y1561004D02*
X270044Y1561272D01*
X269837Y1561502D01*
X269734Y1561809D01*
X269837Y1562077D01*
X270044Y1562269D01*
X270354Y1562422D01*
X270715Y1562460D01*
X271025Y1562422D01*
X271335Y1562269D01*
X271594Y1562039D01*
X271697Y1561770D01*
X271594Y1561464D01*
X271284Y1561195D01*
X270819Y1561042D01*
X270302Y1561004D01*
X269630Y1561080D01*
X269269Y1561195D01*
X268907Y1561387D01*
X268649Y1561655D01*
X268597Y1561924D01*
X268700Y1562192D01*
X268959Y1562384D01*
G01X271335Y1564180D02*
X271594Y1564449D01*
X271697Y1564755D01*
X271594Y1565062D01*
X271284Y1565330D01*
X270819Y1565522D01*
X270354Y1565599D01*
X269785D01*
X269320Y1565522D01*
X268907Y1565330D01*
X268700Y1565100D01*
X268597Y1564832D01*
X268700Y1564525D01*
X268907Y1564295D01*
X269217Y1564142D01*
X269630Y1564065D01*
X269992Y1564142D01*
X270354Y1564334D01*
X270560Y1564564D01*
X270612Y1564832D01*
X270509Y1565139D01*
X270250Y1565369D01*
X269785Y1565599D01*
G01X291175Y1564026D02*
X288175D01*
G01X288075Y1560926D02*
Y1567126D01*
X291275D01*
Y1560926D01*
X288075D01*
G01X273998Y1559475D02*
X273843Y1559245D01*
X273740Y1558977D01*
Y1558670D01*
X273895Y1558325D01*
X274153Y1558057D01*
X274463Y1557865D01*
X274980Y1557712D01*
X275445Y1557674D01*
X275910Y1557750D01*
X276220Y1557865D01*
X276530Y1558095D01*
X276737Y1558364D01*
X276840Y1558632D01*
Y1558900D01*
X276737Y1559169D01*
X276582Y1559399D01*
X276375Y1559590D01*
G01X275548Y1561004D02*
X275187Y1561272D01*
X274980Y1561502D01*
X274877Y1561809D01*
X274980Y1562077D01*
X275187Y1562269D01*
X275497Y1562422D01*
X275858Y1562460D01*
X276168Y1562422D01*
X276478Y1562269D01*
X276737Y1562039D01*
X276840Y1561770D01*
X276737Y1561464D01*
X276427Y1561195D01*
X275962Y1561042D01*
X275445Y1561004D01*
X274773Y1561080D01*
X274412Y1561195D01*
X274050Y1561387D01*
X273792Y1561655D01*
X273740Y1561924D01*
X273843Y1562192D01*
X274102Y1562384D01*
G01X276840Y1564832D02*
X276788Y1565100D01*
X276633Y1565407D01*
X276375Y1565599D01*
X276013Y1565675D01*
X275652Y1565599D01*
X275342Y1565369D01*
X275187Y1565024D01*
Y1564640D01*
X275083Y1564410D01*
X274825Y1564219D01*
X274463Y1564142D01*
X274102Y1564257D01*
X273843Y1564525D01*
X273740Y1564832D01*
X273843Y1565139D01*
X274102Y1565407D01*
X274463Y1565522D01*
X274825Y1565445D01*
X275083Y1565254D01*
X275187Y1565024D01*
Y1564640D01*
X275342Y1564295D01*
X275652Y1564065D01*
X276013Y1563989D01*
X276375Y1564065D01*
X276633Y1564257D01*
X276788Y1564564D01*
X276840Y1564832D01*
G01X286554Y1564026D02*
X283554D01*
G01X283454Y1560926D02*
Y1567126D01*
X286654D01*
Y1560926D01*
X283454D01*
G01X287770Y1649549D02*
X287615Y1649319D01*
X287512Y1649051D01*
Y1648744D01*
X287667Y1648399D01*
X287925Y1648131D01*
X288235Y1647939D01*
X288752Y1647786D01*
X289217Y1647748D01*
X289682Y1647824D01*
X289992Y1647939D01*
X290302Y1648169D01*
X290509Y1648438D01*
X290612Y1648706D01*
Y1648974D01*
X290509Y1649243D01*
X290354Y1649473D01*
X290147Y1649664D01*
G01X289320Y1651078D02*
X288959Y1651346D01*
X288752Y1651576D01*
X288649Y1651883D01*
X288752Y1652151D01*
X288959Y1652343D01*
X289269Y1652496D01*
X289630Y1652534D01*
X289940Y1652496D01*
X290250Y1652343D01*
X290509Y1652113D01*
X290612Y1651844D01*
X290509Y1651538D01*
X290199Y1651269D01*
X289734Y1651116D01*
X289217Y1651078D01*
X288545Y1651154D01*
X288184Y1651269D01*
X287822Y1651461D01*
X287564Y1651729D01*
X287512Y1651998D01*
X287615Y1652266D01*
X287874Y1652458D01*
G01X290147Y1654063D02*
X290405Y1654293D01*
X290560Y1654561D01*
X290612Y1654906D01*
X290509Y1655251D01*
X290302Y1655519D01*
X289940Y1655711D01*
X289527Y1655749D01*
X289114Y1655673D01*
X288855Y1655481D01*
X288649Y1655213D01*
X288597Y1654944D01*
X288649Y1654676D01*
X288855Y1654331D01*
X287512Y1654446D01*
Y1655481D01*
G01X287921Y1635743D02*
X290921D01*
G01X291021Y1638843D02*
Y1632643D01*
X287821D01*
Y1638843D01*
X291021D01*
G01X283002Y1649621D02*
X282847Y1649391D01*
X282744Y1649123D01*
Y1648816D01*
X282899Y1648471D01*
X283157Y1648203D01*
X283467Y1648011D01*
X283984Y1647858D01*
X284449Y1647820D01*
X284914Y1647896D01*
X285224Y1648011D01*
X285534Y1648241D01*
X285741Y1648510D01*
X285844Y1648778D01*
Y1649046D01*
X285741Y1649315D01*
X285586Y1649545D01*
X285379Y1649736D01*
G01X284552Y1651150D02*
X284191Y1651418D01*
X283984Y1651648D01*
X283881Y1651955D01*
X283984Y1652223D01*
X284191Y1652415D01*
X284501Y1652568D01*
X284862Y1652606D01*
X285172Y1652568D01*
X285482Y1652415D01*
X285741Y1652185D01*
X285844Y1651916D01*
X285741Y1651610D01*
X285431Y1651341D01*
X284966Y1651188D01*
X284449Y1651150D01*
X283777Y1651226D01*
X283416Y1651341D01*
X283054Y1651533D01*
X282796Y1651801D01*
X282744Y1652070D01*
X282847Y1652338D01*
X283106Y1652530D01*
G01X285844Y1655438D02*
X282744D01*
X284966Y1654020D01*
Y1655936D01*
G01X286386Y1642843D02*
Y1632643D01*
X281786D01*
Y1642843D01*
X286386D01*
G01Y1637743D02*
X281786D01*
G01X338582Y1693504D02*
G03I-31496J0D01*
G01X282031Y1720171D02*
Y1723271D01*
G01X283641D02*
Y1720171D01*
G01Y1721721D02*
X282031D01*
G01X285093Y1720791D02*
X285323Y1720429D01*
X285629Y1720223D01*
X285974Y1720171D01*
X286281Y1720223D01*
X286588Y1720481D01*
X286779Y1720791D01*
X286818Y1721101D01*
X286741Y1721463D01*
X286473Y1721721D01*
X286204Y1721824D01*
X285859D01*
G01X286204D02*
X286434Y1721979D01*
X286626Y1722238D01*
X286703Y1722548D01*
X286626Y1722858D01*
X286434Y1723116D01*
X286089Y1723271D01*
X285744Y1723219D01*
X285399Y1723013D01*
G01X288803Y1730163D02*
X288648Y1729933D01*
X288545Y1729665D01*
Y1729358D01*
X288700Y1729013D01*
X288958Y1728745D01*
X289268Y1728553D01*
X289785Y1728400D01*
X290250Y1728362D01*
X290715Y1728438D01*
X291025Y1728553D01*
X291335Y1728783D01*
X291542Y1729052D01*
X291645Y1729320D01*
Y1729588D01*
X291542Y1729857D01*
X291387Y1730087D01*
X291180Y1730278D01*
G01X291645Y1732343D02*
X290973Y1732420D01*
X290405Y1732535D01*
X289888Y1732688D01*
X289320Y1732880D01*
X288545Y1733187D01*
Y1731653D01*
G01X291645Y1735980D02*
X288545D01*
X290767Y1734562D01*
Y1736478D01*
G01X290999Y1743490D02*
X287999D01*
G01X287899Y1740390D02*
Y1746590D01*
X291099D01*
Y1740390D01*
X287899D01*
G01X283657Y1730163D02*
X283502Y1729933D01*
X283399Y1729665D01*
Y1729358D01*
X283554Y1729013D01*
X283812Y1728745D01*
X284122Y1728553D01*
X284639Y1728400D01*
X285104Y1728362D01*
X285569Y1728438D01*
X285879Y1728553D01*
X286189Y1728783D01*
X286396Y1729052D01*
X286499Y1729320D01*
Y1729588D01*
X286396Y1729857D01*
X286241Y1730087D01*
X286034Y1730278D01*
G01X286499Y1732343D02*
X285827Y1732420D01*
X285259Y1732535D01*
X284742Y1732688D01*
X284174Y1732880D01*
X283399Y1733187D01*
Y1731653D01*
G01X286034Y1734677D02*
X286292Y1734907D01*
X286447Y1735175D01*
X286499Y1735520D01*
X286396Y1735865D01*
X286189Y1736133D01*
X285827Y1736325D01*
X285414Y1736363D01*
X285001Y1736287D01*
X284742Y1736095D01*
X284536Y1735827D01*
X284484Y1735558D01*
X284536Y1735290D01*
X284742Y1734945D01*
X283399Y1735060D01*
Y1736095D01*
G01X286083Y1743490D02*
X283083D01*
G01X282983Y1740390D02*
Y1746590D01*
X286183D01*
Y1740390D01*
X282983D01*
G01X273511Y1730378D02*
X273356Y1730148D01*
X273253Y1729880D01*
Y1729573D01*
X273408Y1729228D01*
X273666Y1728960D01*
X273976Y1728768D01*
X274493Y1728615D01*
X274958Y1728577D01*
X275423Y1728653D01*
X275733Y1728768D01*
X276043Y1728998D01*
X276250Y1729267D01*
X276353Y1729535D01*
Y1729803D01*
X276250Y1730072D01*
X276095Y1730302D01*
X275888Y1730493D01*
G01X276353Y1732558D02*
X275681Y1732635D01*
X275113Y1732750D01*
X274596Y1732903D01*
X274028Y1733095D01*
X273253Y1733402D01*
Y1731868D01*
G01X276353Y1735658D02*
X275681Y1735735D01*
X275113Y1735850D01*
X274596Y1736003D01*
X274028Y1736195D01*
X273253Y1736502D01*
Y1734968D01*
G01X276204Y1743490D02*
X273204D01*
G01X273104Y1740390D02*
Y1746590D01*
X276304D01*
Y1740390D01*
X273104D01*
G01X278784Y1730234D02*
X278629Y1730004D01*
X278526Y1729736D01*
Y1729429D01*
X278681Y1729084D01*
X278939Y1728816D01*
X279249Y1728624D01*
X279766Y1728471D01*
X280231Y1728433D01*
X280696Y1728509D01*
X281006Y1728624D01*
X281316Y1728854D01*
X281523Y1729123D01*
X281626Y1729391D01*
Y1729659D01*
X281523Y1729928D01*
X281368Y1730158D01*
X281161Y1730349D01*
G01X281626Y1732414D02*
X280954Y1732491D01*
X280386Y1732606D01*
X279869Y1732759D01*
X279301Y1732951D01*
X278526Y1733258D01*
Y1731724D01*
G01X280334Y1734863D02*
X279973Y1735131D01*
X279766Y1735361D01*
X279663Y1735668D01*
X279766Y1735936D01*
X279973Y1736128D01*
X280283Y1736281D01*
X280644Y1736319D01*
X280954Y1736281D01*
X281264Y1736128D01*
X281523Y1735898D01*
X281626Y1735629D01*
X281523Y1735323D01*
X281213Y1735054D01*
X280748Y1734901D01*
X280231Y1734863D01*
X279559Y1734939D01*
X279198Y1735054D01*
X278836Y1735246D01*
X278578Y1735514D01*
X278526Y1735783D01*
X278629Y1736051D01*
X278888Y1736243D01*
G01X281203Y1743490D02*
X278203D01*
G01X278103Y1740390D02*
Y1746590D01*
X281303D01*
Y1740390D01*
X278103D01*
G01X285123Y1809971D02*
X288123D01*
G01X288223Y1813071D02*
Y1806871D01*
X285023D01*
Y1813071D01*
X288223D01*
G01X290050Y1809971D02*
X293050D01*
G01X293150Y1813071D02*
Y1806871D01*
X289950D01*
Y1813071D01*
X293150D01*
G01X283366Y1817071D02*
Y1806871D01*
X278766D01*
Y1817071D01*
X283366D01*
G01Y1811971D02*
X278766D01*
G01X286271Y1823628D02*
X286116Y1823398D01*
X286013Y1823130D01*
Y1822823D01*
X286168Y1822478D01*
X286426Y1822210D01*
X286736Y1822018D01*
X287253Y1821865D01*
X287718Y1821827D01*
X288183Y1821903D01*
X288493Y1822018D01*
X288803Y1822248D01*
X289010Y1822517D01*
X289113Y1822785D01*
Y1823053D01*
X289010Y1823322D01*
X288855Y1823552D01*
X288648Y1823743D01*
G01X289113Y1825808D02*
X288441Y1825885D01*
X287873Y1826000D01*
X287356Y1826153D01*
X286788Y1826345D01*
X286013Y1826652D01*
Y1825118D01*
G01X286530Y1828257D02*
X286220Y1828487D01*
X286065Y1828755D01*
X286013Y1829062D01*
X286116Y1829445D01*
X286375Y1829713D01*
X286685Y1829790D01*
X286995Y1829752D01*
X287253Y1829598D01*
X287770Y1828832D01*
X288131Y1828487D01*
X288648Y1828257D01*
X289113Y1828180D01*
Y1829790D01*
G01X281304Y1823628D02*
X281149Y1823398D01*
X281046Y1823130D01*
Y1822823D01*
X281201Y1822478D01*
X281459Y1822210D01*
X281769Y1822018D01*
X282286Y1821865D01*
X282751Y1821827D01*
X283216Y1821903D01*
X283526Y1822018D01*
X283836Y1822248D01*
X284043Y1822517D01*
X284146Y1822785D01*
Y1823053D01*
X284043Y1823322D01*
X283888Y1823552D01*
X283681Y1823743D01*
G01X284146Y1825808D02*
X283474Y1825885D01*
X282906Y1826000D01*
X282389Y1826153D01*
X281821Y1826345D01*
X281046Y1826652D01*
Y1825118D01*
G01X284146Y1828985D02*
X281046D01*
X281666Y1828525D01*
G01X284146D02*
Y1829445D01*
G01X283976Y1867292D02*
Y1870392D01*
X284935D01*
X285241Y1870237D01*
X285433Y1870030D01*
X285510Y1869617D01*
X285433Y1869204D01*
X285203Y1868945D01*
X284935Y1868790D01*
X283976D01*
G01X284935D02*
X285510Y1867292D01*
G01X287843D02*
Y1870392D01*
X287383Y1869772D01*
G01Y1867292D02*
X288303D01*
G01X290100Y1867912D02*
X290330Y1867550D01*
X290636Y1867344D01*
X290981Y1867292D01*
X291288Y1867344D01*
X291595Y1867602D01*
X291786Y1867912D01*
X291825Y1868222D01*
X291748Y1868584D01*
X291480Y1868842D01*
X291211Y1868945D01*
X290866D01*
G01X291211D02*
X291441Y1869100D01*
X291633Y1869359D01*
X291710Y1869669D01*
X291633Y1869979D01*
X291441Y1870237D01*
X291096Y1870392D01*
X290751Y1870340D01*
X290406Y1870134D01*
G01X294043Y1867292D02*
Y1870392D01*
X293583Y1869772D01*
G01Y1867292D02*
X294503D01*
G01X290237Y1862965D02*
X284037D01*
Y1866165D01*
X290237D01*
Y1862965D01*
G01X283187Y1852797D02*
Y1855897D01*
X284146D01*
X284452Y1855742D01*
X284644Y1855535D01*
X284721Y1855122D01*
X284644Y1854709D01*
X284414Y1854450D01*
X284146Y1854295D01*
X283187D01*
G01X284146D02*
X284721Y1852797D01*
G01X287054D02*
Y1855897D01*
X286594Y1855277D01*
G01Y1852797D02*
X287514D01*
G01X289311Y1853417D02*
X289541Y1853055D01*
X289847Y1852849D01*
X290192Y1852797D01*
X290499Y1852849D01*
X290806Y1853107D01*
X290997Y1853417D01*
X291036Y1853727D01*
X290959Y1854089D01*
X290691Y1854347D01*
X290422Y1854450D01*
X290077D01*
G01X290422D02*
X290652Y1854605D01*
X290844Y1854864D01*
X290921Y1855174D01*
X290844Y1855484D01*
X290652Y1855742D01*
X290307Y1855897D01*
X289962Y1855845D01*
X289617Y1855639D01*
G01X292526Y1855380D02*
X292756Y1855690D01*
X293024Y1855845D01*
X293331Y1855897D01*
X293714Y1855794D01*
X293982Y1855535D01*
X294059Y1855225D01*
X294021Y1854915D01*
X293867Y1854657D01*
X293101Y1854140D01*
X292756Y1853779D01*
X292526Y1853262D01*
X292449Y1852797D01*
X294059D01*
G01X290319Y1857068D02*
X284119D01*
Y1860268D01*
X290319D01*
Y1857068D01*
G01X284598Y1891886D02*
Y1894986D01*
G01X286208D02*
Y1891886D01*
G01Y1893436D02*
X284598D01*
G01X288503Y1891886D02*
Y1894986D01*
X288043Y1894366D01*
G01Y1891886D02*
X288963D01*
G01X290760Y1892506D02*
X290990Y1892144D01*
X291296Y1891938D01*
X291641Y1891886D01*
X291948Y1891938D01*
X292255Y1892196D01*
X292446Y1892506D01*
X292485Y1892816D01*
X292408Y1893178D01*
X292140Y1893436D01*
X291871Y1893539D01*
X291526D01*
G01X291871D02*
X292101Y1893694D01*
X292293Y1893953D01*
X292370Y1894263D01*
X292293Y1894573D01*
X292101Y1894831D01*
X291756Y1894986D01*
X291411Y1894934D01*
X291066Y1894728D01*
G01X286946Y1903859D02*
X286791Y1903629D01*
X286688Y1903361D01*
Y1903054D01*
X286843Y1902709D01*
X287101Y1902441D01*
X287411Y1902249D01*
X287928Y1902096D01*
X288393Y1902058D01*
X288858Y1902134D01*
X289168Y1902249D01*
X289478Y1902479D01*
X289685Y1902748D01*
X289788Y1903016D01*
Y1903284D01*
X289685Y1903553D01*
X289530Y1903783D01*
X289323Y1903974D01*
G01X289788Y1906116D02*
X289736Y1906384D01*
X289581Y1906691D01*
X289323Y1906883D01*
X288961Y1906959D01*
X288600Y1906883D01*
X288290Y1906653D01*
X288135Y1906308D01*
Y1905924D01*
X288031Y1905694D01*
X287773Y1905503D01*
X287411Y1905426D01*
X287050Y1905541D01*
X286791Y1905809D01*
X286688Y1906116D01*
X286791Y1906423D01*
X287050Y1906691D01*
X287411Y1906806D01*
X287773Y1906729D01*
X288031Y1906538D01*
X288135Y1906308D01*
Y1905924D01*
X288290Y1905579D01*
X288600Y1905349D01*
X288961Y1905273D01*
X289323Y1905349D01*
X289581Y1905541D01*
X289736Y1905848D01*
X289788Y1906116D01*
G01Y1909216D02*
X286688D01*
X287308Y1908756D01*
G01X289788D02*
Y1909676D01*
G01X285521Y1915370D02*
Y1921570D01*
X288721D01*
Y1915370D01*
X285521D01*
G01X282156Y1904074D02*
X282001Y1903844D01*
X281898Y1903576D01*
Y1903269D01*
X282053Y1902924D01*
X282311Y1902656D01*
X282621Y1902464D01*
X283138Y1902311D01*
X283603Y1902273D01*
X284068Y1902349D01*
X284378Y1902464D01*
X284688Y1902694D01*
X284895Y1902963D01*
X284998Y1903231D01*
Y1903499D01*
X284895Y1903768D01*
X284740Y1903998D01*
X284533Y1904189D01*
G01X284998Y1906331D02*
X284946Y1906599D01*
X284791Y1906906D01*
X284533Y1907098D01*
X284171Y1907174D01*
X283810Y1907098D01*
X283500Y1906868D01*
X283345Y1906523D01*
Y1906139D01*
X283241Y1905909D01*
X282983Y1905718D01*
X282621Y1905641D01*
X282260Y1905756D01*
X282001Y1906024D01*
X281898Y1906331D01*
X282001Y1906638D01*
X282260Y1906906D01*
X282621Y1907021D01*
X282983Y1906944D01*
X283241Y1906753D01*
X283345Y1906523D01*
Y1906139D01*
X283500Y1905794D01*
X283810Y1905564D01*
X284171Y1905488D01*
X284533Y1905564D01*
X284791Y1905756D01*
X284946Y1906063D01*
X284998Y1906331D01*
G01X282415Y1908703D02*
X282105Y1908933D01*
X281950Y1909201D01*
X281898Y1909508D01*
X282001Y1909891D01*
X282260Y1910159D01*
X282570Y1910236D01*
X282880Y1910198D01*
X283138Y1910044D01*
X283655Y1909278D01*
X284016Y1908933D01*
X284533Y1908703D01*
X284998Y1908626D01*
Y1910236D01*
G01X281117Y1915370D02*
Y1921570D01*
X284317D01*
Y1915370D01*
X281117D01*
G01X277091Y1904288D02*
X276936Y1904058D01*
X276833Y1903790D01*
Y1903483D01*
X276988Y1903138D01*
X277246Y1902870D01*
X277556Y1902678D01*
X278073Y1902525D01*
X278538Y1902487D01*
X279003Y1902563D01*
X279313Y1902678D01*
X279623Y1902908D01*
X279830Y1903177D01*
X279933Y1903445D01*
Y1903713D01*
X279830Y1903982D01*
X279675Y1904212D01*
X279468Y1904403D01*
G01X279933Y1906545D02*
X279881Y1906813D01*
X279726Y1907120D01*
X279468Y1907312D01*
X279106Y1907388D01*
X278745Y1907312D01*
X278435Y1907082D01*
X278280Y1906737D01*
Y1906353D01*
X278176Y1906123D01*
X277918Y1905932D01*
X277556Y1905855D01*
X277195Y1905970D01*
X276936Y1906238D01*
X276833Y1906545D01*
X276936Y1906852D01*
X277195Y1907120D01*
X277556Y1907235D01*
X277918Y1907158D01*
X278176Y1906967D01*
X278280Y1906737D01*
Y1906353D01*
X278435Y1906008D01*
X278745Y1905778D01*
X279106Y1905702D01*
X279468Y1905778D01*
X279726Y1905970D01*
X279881Y1906277D01*
X279933Y1906545D01*
G01X279313Y1908802D02*
X279675Y1909032D01*
X279881Y1909338D01*
X279933Y1909683D01*
X279881Y1909990D01*
X279623Y1910297D01*
X279313Y1910488D01*
X279003Y1910527D01*
X278641Y1910450D01*
X278383Y1910182D01*
X278280Y1909913D01*
Y1909568D01*
G01Y1909913D02*
X278125Y1910143D01*
X277866Y1910335D01*
X277556Y1910412D01*
X277246Y1910335D01*
X276988Y1910143D01*
X276833Y1909798D01*
X276885Y1909453D01*
X277091Y1909108D01*
G01X276662Y1915370D02*
Y1921570D01*
X279862D01*
Y1915370D01*
X276662D01*
G01X271795Y1904360D02*
X271640Y1904130D01*
X271537Y1903862D01*
Y1903555D01*
X271692Y1903210D01*
X271950Y1902942D01*
X272260Y1902750D01*
X272777Y1902597D01*
X273242Y1902559D01*
X273707Y1902635D01*
X274017Y1902750D01*
X274327Y1902980D01*
X274534Y1903249D01*
X274637Y1903517D01*
Y1903785D01*
X274534Y1904054D01*
X274379Y1904284D01*
X274172Y1904475D01*
G01X274637Y1906617D02*
X274585Y1906885D01*
X274430Y1907192D01*
X274172Y1907384D01*
X273810Y1907460D01*
X273449Y1907384D01*
X273139Y1907154D01*
X272984Y1906809D01*
Y1906425D01*
X272880Y1906195D01*
X272622Y1906004D01*
X272260Y1905927D01*
X271899Y1906042D01*
X271640Y1906310D01*
X271537Y1906617D01*
X271640Y1906924D01*
X271899Y1907192D01*
X272260Y1907307D01*
X272622Y1907230D01*
X272880Y1907039D01*
X272984Y1906809D01*
Y1906425D01*
X273139Y1906080D01*
X273449Y1905850D01*
X273810Y1905774D01*
X274172Y1905850D01*
X274430Y1906042D01*
X274585Y1906349D01*
X274637Y1906617D01*
G01Y1910177D02*
X271537D01*
X273759Y1908759D01*
Y1910675D01*
G01X272217Y1915370D02*
Y1921570D01*
X275417D01*
Y1915370D01*
X272217D01*
G01X288621Y1918470D02*
X285621D01*
G01X284217D02*
X281217D01*
G01X279762D02*
X276762D01*
G01X275317D02*
X272317D01*
G01X338583Y2043503D02*
G03I-31496J0D01*
G01X284311Y2071510D02*
Y2074610D01*
G01X285921D02*
Y2071510D01*
G01Y2073060D02*
X284311D01*
G01X288216Y2071510D02*
Y2074610D01*
X287756Y2073990D01*
G01Y2071510D02*
X288676D01*
G01X305751Y61918D02*
Y55718D01*
X302551D01*
Y61918D01*
X305751D01*
G01X310251D02*
Y55718D01*
X307051D01*
Y61918D01*
X310251D01*
G01X314689D02*
Y55718D01*
X311489D01*
Y61918D01*
X314689D01*
G01X301287D02*
Y55718D01*
X298087D01*
Y61918D01*
X301287D01*
G01X296783Y65918D02*
Y55718D01*
X292183D01*
Y65918D01*
X296783D01*
G01X302314Y67706D02*
X302159Y67476D01*
X302056Y67208D01*
Y66901D01*
X302211Y66556D01*
X302469Y66288D01*
X302779Y66096D01*
X303296Y65943D01*
X303761Y65905D01*
X304226Y65981D01*
X304536Y66096D01*
X304846Y66326D01*
X305053Y66595D01*
X305156Y66863D01*
Y67131D01*
X305053Y67400D01*
X304898Y67630D01*
X304691Y67821D01*
G01X304536Y69120D02*
X304898Y69350D01*
X305104Y69656D01*
X305156Y70001D01*
X305104Y70308D01*
X304846Y70615D01*
X304536Y70806D01*
X304226Y70845D01*
X303864Y70768D01*
X303606Y70500D01*
X303503Y70231D01*
Y69886D01*
G01Y70231D02*
X303348Y70461D01*
X303089Y70653D01*
X302779Y70730D01*
X302469Y70653D01*
X302211Y70461D01*
X302056Y70116D01*
X302108Y69771D01*
X302314Y69426D01*
G01X302651Y58818D02*
X305651D01*
G01X307066Y67706D02*
X306911Y67476D01*
X306808Y67208D01*
Y66901D01*
X306963Y66556D01*
X307221Y66288D01*
X307531Y66096D01*
X308048Y65943D01*
X308513Y65905D01*
X308978Y65981D01*
X309288Y66096D01*
X309598Y66326D01*
X309805Y66595D01*
X309908Y66863D01*
Y67131D01*
X309805Y67400D01*
X309650Y67630D01*
X309443Y67821D01*
G01X309908Y70423D02*
X306808D01*
X309030Y69005D01*
Y70921D01*
G01X307151Y58818D02*
X310151D01*
G01X311542Y67706D02*
X311387Y67476D01*
X311284Y67208D01*
Y66901D01*
X311439Y66556D01*
X311697Y66288D01*
X312007Y66096D01*
X312524Y65943D01*
X312989Y65905D01*
X313454Y65981D01*
X313764Y66096D01*
X314074Y66326D01*
X314281Y66595D01*
X314384Y66863D01*
Y67131D01*
X314281Y67400D01*
X314126Y67630D01*
X313919Y67821D01*
G01Y69120D02*
X314177Y69350D01*
X314332Y69618D01*
X314384Y69963D01*
X314281Y70308D01*
X314074Y70576D01*
X313712Y70768D01*
X313299Y70806D01*
X312886Y70730D01*
X312627Y70538D01*
X312421Y70270D01*
X312369Y70001D01*
X312421Y69733D01*
X312627Y69388D01*
X311284Y69503D01*
Y70538D01*
G01X311589Y58818D02*
X314589D01*
G01X298064Y67706D02*
X297909Y67476D01*
X297806Y67208D01*
Y66901D01*
X297961Y66556D01*
X298219Y66288D01*
X298529Y66096D01*
X299046Y65943D01*
X299511Y65905D01*
X299976Y65981D01*
X300286Y66096D01*
X300596Y66326D01*
X300803Y66595D01*
X300906Y66863D01*
Y67131D01*
X300803Y67400D01*
X300648Y67630D01*
X300441Y67821D01*
G01X298323Y69235D02*
X298013Y69465D01*
X297858Y69733D01*
X297806Y70040D01*
X297909Y70423D01*
X298168Y70691D01*
X298478Y70768D01*
X298788Y70730D01*
X299046Y70576D01*
X299563Y69810D01*
X299924Y69465D01*
X300441Y69235D01*
X300906Y69158D01*
Y70768D01*
G01X298187Y58818D02*
X301187D01*
G01X293329Y70967D02*
X293174Y70737D01*
X293071Y70469D01*
Y70162D01*
X293226Y69817D01*
X293484Y69549D01*
X293794Y69357D01*
X294311Y69204D01*
X294776Y69166D01*
X295241Y69242D01*
X295551Y69357D01*
X295861Y69587D01*
X296068Y69856D01*
X296171Y70124D01*
Y70392D01*
X296068Y70661D01*
X295913Y70891D01*
X295706Y71082D01*
G01X296171Y73224D02*
X293071D01*
X293691Y72764D01*
G01X296171D02*
Y73684D01*
G01X296783Y60818D02*
X292183D01*
G01X300541Y165100D02*
X300386Y164870D01*
X300283Y164602D01*
Y164295D01*
X300438Y163950D01*
X300696Y163682D01*
X301006Y163490D01*
X301523Y163337D01*
X301988Y163299D01*
X302453Y163375D01*
X302763Y163490D01*
X303073Y163720D01*
X303280Y163989D01*
X303383Y164257D01*
Y164525D01*
X303280Y164794D01*
X303125Y165024D01*
X302918Y165215D01*
G01X303383Y167357D02*
X300283D01*
X300903Y166897D01*
G01X303383D02*
Y167817D01*
G01Y170917D02*
X300283D01*
X302505Y169499D01*
Y171415D01*
G01X304737Y165346D02*
X304582Y165116D01*
X304479Y164848D01*
Y164541D01*
X304634Y164196D01*
X304892Y163928D01*
X305202Y163736D01*
X305719Y163583D01*
X306184Y163545D01*
X306649Y163621D01*
X306959Y163736D01*
X307269Y163966D01*
X307476Y164235D01*
X307579Y164503D01*
Y164771D01*
X307476Y165040D01*
X307321Y165270D01*
X307114Y165461D01*
G01X307579Y167603D02*
X304479D01*
X305099Y167143D01*
G01X307579D02*
Y168063D01*
G01X306959Y169860D02*
X307321Y170090D01*
X307527Y170396D01*
X307579Y170741D01*
X307527Y171048D01*
X307269Y171355D01*
X306959Y171546D01*
X306649Y171585D01*
X306287Y171508D01*
X306029Y171240D01*
X305926Y170971D01*
Y170626D01*
G01Y170971D02*
X305771Y171201D01*
X305512Y171393D01*
X305202Y171470D01*
X304892Y171393D01*
X304634Y171201D01*
X304479Y170856D01*
X304531Y170511D01*
X304737Y170166D01*
G01X309080Y165442D02*
X308925Y165212D01*
X308822Y164944D01*
Y164637D01*
X308977Y164292D01*
X309235Y164024D01*
X309545Y163832D01*
X310062Y163679D01*
X310527Y163641D01*
X310992Y163717D01*
X311302Y163832D01*
X311612Y164062D01*
X311819Y164331D01*
X311922Y164599D01*
Y164867D01*
X311819Y165136D01*
X311664Y165366D01*
X311457Y165557D01*
G01X311922Y167699D02*
X308822D01*
X309442Y167239D01*
G01X311922D02*
Y168159D01*
G01X309339Y170071D02*
X309029Y170301D01*
X308874Y170569D01*
X308822Y170876D01*
X308925Y171259D01*
X309184Y171527D01*
X309494Y171604D01*
X309804Y171566D01*
X310062Y171412D01*
X310579Y170646D01*
X310940Y170301D01*
X311457Y170071D01*
X311922Y169994D01*
Y171604D01*
G01X313133Y165539D02*
X312978Y165309D01*
X312875Y165041D01*
Y164734D01*
X313030Y164389D01*
X313288Y164121D01*
X313598Y163929D01*
X314115Y163776D01*
X314580Y163738D01*
X315045Y163814D01*
X315355Y163929D01*
X315665Y164159D01*
X315872Y164428D01*
X315975Y164696D01*
Y164964D01*
X315872Y165233D01*
X315717Y165463D01*
X315510Y165654D01*
G01X315975Y167796D02*
X312875D01*
X313495Y167336D01*
G01X315975D02*
Y168256D01*
G01Y170896D02*
X312875D01*
X313495Y170436D01*
G01X315975D02*
Y171356D01*
G01X298023Y167839D02*
X295023D01*
G01X294923Y164739D02*
Y170939D01*
X298123D01*
Y164739D01*
X294923D01*
G01X320536Y308267D02*
G03I-13450J0D01*
G01X293814Y327679D02*
X293659Y327449D01*
X293556Y327181D01*
Y326874D01*
X293711Y326529D01*
X293969Y326261D01*
X294279Y326069D01*
X294796Y325916D01*
X295261Y325878D01*
X295726Y325954D01*
X296036Y326069D01*
X296346Y326299D01*
X296553Y326568D01*
X296656Y326836D01*
Y327104D01*
X296553Y327373D01*
X296398Y327603D01*
X296191Y327794D01*
G01X296656Y329936D02*
X293556D01*
X294176Y329476D01*
G01X296656D02*
Y330396D01*
G01Y333036D02*
X296604Y333304D01*
X296449Y333611D01*
X296191Y333803D01*
X295829Y333879D01*
X295468Y333803D01*
X295158Y333573D01*
X295003Y333228D01*
Y332844D01*
X294899Y332614D01*
X294641Y332423D01*
X294279Y332346D01*
X293918Y332461D01*
X293659Y332729D01*
X293556Y333036D01*
X293659Y333343D01*
X293918Y333611D01*
X294279Y333726D01*
X294641Y333649D01*
X294899Y333458D01*
X295003Y333228D01*
Y332844D01*
X295158Y332499D01*
X295468Y332269D01*
X295829Y332193D01*
X296191Y332269D01*
X296449Y332461D01*
X296604Y332768D01*
X296656Y333036D01*
G01X296006Y343092D02*
X293006D01*
G01X292906Y339992D02*
Y346192D01*
X296106D01*
Y339992D01*
X292906D01*
G01X292950Y322844D02*
Y325944D01*
G01X294560D02*
Y322844D01*
G01Y324394D02*
X292950D01*
G01X296855Y322844D02*
Y325944D01*
X296395Y325324D01*
G01Y322844D02*
X297315D01*
G01X300415D02*
Y325944D01*
X298997Y323722D01*
X300913D01*
G01X294009Y587062D02*
X297009D01*
G01X297109Y590162D02*
Y583962D01*
X293909D01*
Y590162D01*
X297109D01*
G01X293907Y599443D02*
X293752Y599213D01*
X293649Y598945D01*
Y598638D01*
X293804Y598293D01*
X294062Y598025D01*
X294372Y597833D01*
X294889Y597680D01*
X295354Y597642D01*
X295819Y597718D01*
X296129Y597833D01*
X296439Y598063D01*
X296646Y598332D01*
X296749Y598600D01*
Y598868D01*
X296646Y599137D01*
X296491Y599367D01*
X296284Y599558D01*
G01X294166Y600972D02*
X293856Y601202D01*
X293701Y601470D01*
X293649Y601777D01*
X293752Y602160D01*
X294011Y602428D01*
X294321Y602505D01*
X294631Y602467D01*
X294889Y602313D01*
X295406Y601547D01*
X295767Y601202D01*
X296284Y600972D01*
X296749Y600895D01*
Y602505D01*
G01Y605260D02*
X293649D01*
X295871Y603842D01*
Y605758D01*
G01X293137Y760276D02*
X292982Y760046D01*
X292879Y759778D01*
Y759471D01*
X293034Y759126D01*
X293292Y758858D01*
X293602Y758666D01*
X294119Y758513D01*
X294584Y758475D01*
X295049Y758551D01*
X295359Y758666D01*
X295669Y758896D01*
X295876Y759165D01*
X295979Y759433D01*
Y759701D01*
X295876Y759970D01*
X295721Y760200D01*
X295514Y760391D01*
G01X295359Y761690D02*
X295721Y761920D01*
X295927Y762226D01*
X295979Y762571D01*
X295927Y762878D01*
X295669Y763185D01*
X295359Y763376D01*
X295049Y763415D01*
X294687Y763338D01*
X294429Y763070D01*
X294326Y762801D01*
Y762456D01*
G01Y762801D02*
X294171Y763031D01*
X293912Y763223D01*
X293602Y763300D01*
X293292Y763223D01*
X293034Y763031D01*
X292879Y762686D01*
X292931Y762341D01*
X293137Y761996D01*
G01X292879Y765633D02*
X292982Y765326D01*
X293241Y765096D01*
X293551Y764943D01*
X293964Y764828D01*
X294429Y764790D01*
X294894Y764828D01*
X295307Y764943D01*
X295617Y765096D01*
X295876Y765326D01*
X295979Y765633D01*
X295876Y765940D01*
X295617Y766170D01*
X295307Y766323D01*
X294894Y766438D01*
X294429Y766476D01*
X293964Y766438D01*
X293551Y766323D01*
X293241Y766170D01*
X292982Y765940D01*
X292879Y765633D01*
G01X298236Y760276D02*
X298081Y760046D01*
X297978Y759778D01*
Y759471D01*
X298133Y759126D01*
X298391Y758858D01*
X298701Y758666D01*
X299218Y758513D01*
X299683Y758475D01*
X300148Y758551D01*
X300458Y758666D01*
X300768Y758896D01*
X300975Y759165D01*
X301078Y759433D01*
Y759701D01*
X300975Y759970D01*
X300820Y760200D01*
X300613Y760391D01*
G01X300458Y761690D02*
X300820Y761920D01*
X301026Y762226D01*
X301078Y762571D01*
X301026Y762878D01*
X300768Y763185D01*
X300458Y763376D01*
X300148Y763415D01*
X299786Y763338D01*
X299528Y763070D01*
X299425Y762801D01*
Y762456D01*
G01Y762801D02*
X299270Y763031D01*
X299011Y763223D01*
X298701Y763300D01*
X298391Y763223D01*
X298133Y763031D01*
X297978Y762686D01*
X298030Y762341D01*
X298236Y761996D01*
G01X301078Y765633D02*
X297978D01*
X298598Y765173D01*
G01X301078D02*
Y766093D01*
G01X298072Y860121D02*
Y863221D01*
G01X299682D02*
Y860121D01*
G01Y861671D02*
X298072D01*
G01X301900Y860121D02*
X301977Y860793D01*
X302092Y861361D01*
X302245Y861878D01*
X302437Y862446D01*
X302744Y863221D01*
X301210D01*
G01X294495Y934964D02*
X294340Y934734D01*
X294237Y934466D01*
Y934159D01*
X294392Y933814D01*
X294650Y933546D01*
X294960Y933354D01*
X295477Y933201D01*
X295942Y933163D01*
X296407Y933239D01*
X296717Y933354D01*
X297027Y933584D01*
X297234Y933853D01*
X297337Y934121D01*
Y934389D01*
X297234Y934658D01*
X297079Y934888D01*
X296872Y935079D01*
G01X296717Y936378D02*
X297079Y936608D01*
X297285Y936914D01*
X297337Y937259D01*
X297285Y937566D01*
X297027Y937873D01*
X296717Y938064D01*
X296407Y938103D01*
X296045Y938026D01*
X295787Y937758D01*
X295684Y937489D01*
Y937144D01*
G01Y937489D02*
X295529Y937719D01*
X295270Y937911D01*
X294960Y937988D01*
X294650Y937911D01*
X294392Y937719D01*
X294237Y937374D01*
X294289Y937029D01*
X294495Y936684D01*
G01X297337Y940244D02*
X296665Y940321D01*
X296097Y940436D01*
X295580Y940589D01*
X295012Y940781D01*
X294237Y941088D01*
Y939554D01*
G01X299602Y934964D02*
X299447Y934734D01*
X299344Y934466D01*
Y934159D01*
X299499Y933814D01*
X299757Y933546D01*
X300067Y933354D01*
X300584Y933201D01*
X301049Y933163D01*
X301514Y933239D01*
X301824Y933354D01*
X302134Y933584D01*
X302341Y933853D01*
X302444Y934121D01*
Y934389D01*
X302341Y934658D01*
X302186Y934888D01*
X301979Y935079D01*
G01X301824Y936378D02*
X302186Y936608D01*
X302392Y936914D01*
X302444Y937259D01*
X302392Y937566D01*
X302134Y937873D01*
X301824Y938064D01*
X301514Y938103D01*
X301152Y938026D01*
X300894Y937758D01*
X300791Y937489D01*
Y937144D01*
G01Y937489D02*
X300636Y937719D01*
X300377Y937911D01*
X300067Y937988D01*
X299757Y937911D01*
X299499Y937719D01*
X299344Y937374D01*
X299396Y937029D01*
X299602Y936684D01*
G01X302444Y940321D02*
X302392Y940589D01*
X302237Y940896D01*
X301979Y941088D01*
X301617Y941164D01*
X301256Y941088D01*
X300946Y940858D01*
X300791Y940513D01*
Y940129D01*
X300687Y939899D01*
X300429Y939708D01*
X300067Y939631D01*
X299706Y939746D01*
X299447Y940014D01*
X299344Y940321D01*
X299447Y940628D01*
X299706Y940896D01*
X300067Y941011D01*
X300429Y940934D01*
X300687Y940743D01*
X300791Y940513D01*
Y940129D01*
X300946Y939784D01*
X301256Y939554D01*
X301617Y939478D01*
X301979Y939554D01*
X302237Y939746D01*
X302392Y940053D01*
X302444Y940321D01*
G01X313990Y930971D02*
Y934071D01*
X314910D01*
X315217Y933916D01*
X315447Y933554D01*
X315524Y933141D01*
X315447Y932728D01*
X315255Y932418D01*
X314910Y932263D01*
X313990D01*
G01X317857Y930971D02*
Y934071D01*
X317397Y933451D01*
G01Y930971D02*
X318317D01*
G01X320229Y932263D02*
X320497Y932624D01*
X320727Y932831D01*
X321034Y932934D01*
X321302Y932831D01*
X321494Y932624D01*
X321647Y932314D01*
X321685Y931953D01*
X321647Y931643D01*
X321494Y931333D01*
X321264Y931074D01*
X320995Y930971D01*
X320689Y931074D01*
X320420Y931384D01*
X320267Y931849D01*
X320229Y932366D01*
X320305Y933038D01*
X320420Y933399D01*
X320612Y933761D01*
X320880Y934019D01*
X321149Y934071D01*
X321417Y933968D01*
X321609Y933709D01*
G01X294112Y1021086D02*
X293957Y1020856D01*
X293854Y1020588D01*
Y1020281D01*
X294009Y1019936D01*
X294267Y1019668D01*
X294577Y1019476D01*
X295094Y1019323D01*
X295559Y1019285D01*
X296024Y1019361D01*
X296334Y1019476D01*
X296644Y1019706D01*
X296851Y1019975D01*
X296954Y1020243D01*
Y1020511D01*
X296851Y1020780D01*
X296696Y1021010D01*
X296489Y1021201D01*
G01X296954Y1023803D02*
X293854D01*
X296076Y1022385D01*
Y1024301D01*
G01X295662Y1025715D02*
X295301Y1025983D01*
X295094Y1026213D01*
X294991Y1026520D01*
X295094Y1026788D01*
X295301Y1026980D01*
X295611Y1027133D01*
X295972Y1027171D01*
X296282Y1027133D01*
X296592Y1026980D01*
X296851Y1026750D01*
X296954Y1026481D01*
X296851Y1026175D01*
X296541Y1025906D01*
X296076Y1025753D01*
X295559Y1025715D01*
X294887Y1025791D01*
X294526Y1025906D01*
X294164Y1026098D01*
X293906Y1026366D01*
X293854Y1026635D01*
X293957Y1026903D01*
X294216Y1027095D01*
G01X296117Y1036457D02*
X293117D01*
G01X293017Y1033357D02*
Y1039557D01*
X296217D01*
Y1033357D01*
X293017D01*
G01X302849Y1109418D02*
X302694Y1109188D01*
X302591Y1108920D01*
Y1108613D01*
X302746Y1108268D01*
X303004Y1108000D01*
X303314Y1107808D01*
X303831Y1107655D01*
X304296Y1107617D01*
X304761Y1107693D01*
X305071Y1107808D01*
X305381Y1108038D01*
X305588Y1108307D01*
X305691Y1108575D01*
Y1108843D01*
X305588Y1109112D01*
X305433Y1109342D01*
X305226Y1109533D01*
G01X305691Y1112135D02*
X302591D01*
X304813Y1110717D01*
Y1112633D01*
G01X305691Y1115235D02*
X302591D01*
X304813Y1113817D01*
Y1115733D01*
G01X307522Y1109418D02*
X307367Y1109188D01*
X307264Y1108920D01*
Y1108613D01*
X307419Y1108268D01*
X307677Y1108000D01*
X307987Y1107808D01*
X308504Y1107655D01*
X308969Y1107617D01*
X309434Y1107693D01*
X309744Y1107808D01*
X310054Y1108038D01*
X310261Y1108307D01*
X310364Y1108575D01*
Y1108843D01*
X310261Y1109112D01*
X310106Y1109342D01*
X309899Y1109533D01*
G01X310364Y1112135D02*
X307264D01*
X309486Y1110717D01*
Y1112633D01*
G01X309899Y1113932D02*
X310157Y1114162D01*
X310312Y1114430D01*
X310364Y1114775D01*
X310261Y1115120D01*
X310054Y1115388D01*
X309692Y1115580D01*
X309279Y1115618D01*
X308866Y1115542D01*
X308607Y1115350D01*
X308401Y1115082D01*
X308349Y1114813D01*
X308401Y1114545D01*
X308607Y1114200D01*
X307264Y1114315D01*
Y1115350D01*
G01X291198Y1110851D02*
X294198D01*
G01X294298Y1113951D02*
Y1107751D01*
X291098D01*
Y1113951D01*
X294298D01*
G01X297339Y1109418D02*
X297184Y1109188D01*
X297081Y1108920D01*
Y1108613D01*
X297236Y1108268D01*
X297494Y1108000D01*
X297804Y1107808D01*
X298321Y1107655D01*
X298786Y1107617D01*
X299251Y1107693D01*
X299561Y1107808D01*
X299871Y1108038D01*
X300078Y1108307D01*
X300181Y1108575D01*
Y1108843D01*
X300078Y1109112D01*
X299923Y1109342D01*
X299716Y1109533D01*
G01X300181Y1112135D02*
X297081D01*
X299303Y1110717D01*
Y1112633D01*
G01X299561Y1113932D02*
X299923Y1114162D01*
X300129Y1114468D01*
X300181Y1114813D01*
X300129Y1115120D01*
X299871Y1115427D01*
X299561Y1115618D01*
X299251Y1115657D01*
X298889Y1115580D01*
X298631Y1115312D01*
X298528Y1115043D01*
Y1114698D01*
G01Y1115043D02*
X298373Y1115273D01*
X298114Y1115465D01*
X297804Y1115542D01*
X297494Y1115465D01*
X297236Y1115273D01*
X297081Y1114928D01*
X297133Y1114583D01*
X297339Y1114238D01*
G01X313884Y1155969D02*
Y1159069D01*
X314843D01*
X315149Y1158914D01*
X315341Y1158707D01*
X315418Y1158294D01*
X315341Y1157881D01*
X315111Y1157622D01*
X314843Y1157467D01*
X313884D01*
G01X314843D02*
X315418Y1155969D01*
G01X317751D02*
Y1159069D01*
X317291Y1158449D01*
G01Y1155969D02*
X318211D01*
G01X320123Y1158552D02*
X320353Y1158862D01*
X320621Y1159017D01*
X320928Y1159069D01*
X321311Y1158966D01*
X321579Y1158707D01*
X321656Y1158397D01*
X321618Y1158087D01*
X321464Y1157829D01*
X320698Y1157312D01*
X320353Y1156951D01*
X320123Y1156434D01*
X320046Y1155969D01*
X321656D01*
G01X324411D02*
Y1159069D01*
X322993Y1156847D01*
X324909D01*
G01X314786Y1176193D02*
Y1179293D01*
X315745D01*
X316051Y1179138D01*
X316243Y1178931D01*
X316320Y1178518D01*
X316243Y1178105D01*
X316013Y1177846D01*
X315745Y1177691D01*
X314786D01*
G01X315745D02*
X316320Y1176193D01*
G01X318653D02*
Y1179293D01*
X318193Y1178673D01*
G01Y1176193D02*
X319113D01*
G01X321025Y1178776D02*
X321255Y1179086D01*
X321523Y1179241D01*
X321830Y1179293D01*
X322213Y1179190D01*
X322481Y1178931D01*
X322558Y1178621D01*
X322520Y1178311D01*
X322366Y1178053D01*
X321600Y1177536D01*
X321255Y1177175D01*
X321025Y1176658D01*
X320948Y1176193D01*
X322558D01*
G01X324010Y1176813D02*
X324240Y1176451D01*
X324546Y1176245D01*
X324891Y1176193D01*
X325198Y1176245D01*
X325505Y1176503D01*
X325696Y1176813D01*
X325735Y1177123D01*
X325658Y1177485D01*
X325390Y1177743D01*
X325121Y1177846D01*
X324776D01*
G01X325121D02*
X325351Y1178001D01*
X325543Y1178260D01*
X325620Y1178570D01*
X325543Y1178880D01*
X325351Y1179138D01*
X325006Y1179293D01*
X324661Y1179241D01*
X324316Y1179035D01*
G01X313707Y1208756D02*
X313552Y1208526D01*
X313449Y1208258D01*
Y1207951D01*
X313604Y1207606D01*
X313862Y1207338D01*
X314172Y1207146D01*
X314689Y1206993D01*
X315154Y1206955D01*
X315619Y1207031D01*
X315929Y1207146D01*
X316239Y1207376D01*
X316446Y1207645D01*
X316549Y1207913D01*
Y1208181D01*
X316446Y1208450D01*
X316291Y1208680D01*
X316084Y1208871D01*
G01Y1210170D02*
X316342Y1210400D01*
X316497Y1210668D01*
X316549Y1211013D01*
X316446Y1211358D01*
X316239Y1211626D01*
X315877Y1211818D01*
X315464Y1211856D01*
X315051Y1211780D01*
X314792Y1211588D01*
X314586Y1211320D01*
X314534Y1211051D01*
X314586Y1210783D01*
X314792Y1210438D01*
X313449Y1210553D01*
Y1211588D01*
G01X315929Y1213270D02*
X316291Y1213500D01*
X316497Y1213806D01*
X316549Y1214151D01*
X316497Y1214458D01*
X316239Y1214765D01*
X315929Y1214956D01*
X315619Y1214995D01*
X315257Y1214918D01*
X314999Y1214650D01*
X314896Y1214381D01*
Y1214036D01*
G01Y1214381D02*
X314741Y1214611D01*
X314482Y1214803D01*
X314172Y1214880D01*
X313862Y1214803D01*
X313604Y1214611D01*
X313449Y1214266D01*
X313501Y1213921D01*
X313707Y1213576D01*
G01X295307Y1211889D02*
X292307D01*
G01X292207Y1208789D02*
Y1214989D01*
X295407D01*
Y1208789D01*
X292207D01*
G01X303124Y1208899D02*
X302969Y1208669D01*
X302866Y1208401D01*
Y1208094D01*
X303021Y1207749D01*
X303279Y1207481D01*
X303589Y1207289D01*
X304106Y1207136D01*
X304571Y1207098D01*
X305036Y1207174D01*
X305346Y1207289D01*
X305656Y1207519D01*
X305863Y1207788D01*
X305966Y1208056D01*
Y1208324D01*
X305863Y1208593D01*
X305708Y1208823D01*
X305501Y1209014D01*
G01Y1210313D02*
X305759Y1210543D01*
X305914Y1210811D01*
X305966Y1211156D01*
X305863Y1211501D01*
X305656Y1211769D01*
X305294Y1211961D01*
X304881Y1211999D01*
X304468Y1211923D01*
X304209Y1211731D01*
X304003Y1211463D01*
X303951Y1211194D01*
X304003Y1210926D01*
X304209Y1210581D01*
X302866Y1210696D01*
Y1211731D01*
G01X305501Y1213413D02*
X305759Y1213643D01*
X305914Y1213911D01*
X305966Y1214256D01*
X305863Y1214601D01*
X305656Y1214869D01*
X305294Y1215061D01*
X304881Y1215099D01*
X304468Y1215023D01*
X304209Y1214831D01*
X304003Y1214563D01*
X303951Y1214294D01*
X304003Y1214026D01*
X304209Y1213681D01*
X302866Y1213796D01*
Y1214831D01*
G01X308491Y1208828D02*
X308336Y1208598D01*
X308233Y1208330D01*
Y1208023D01*
X308388Y1207678D01*
X308646Y1207410D01*
X308956Y1207218D01*
X309473Y1207065D01*
X309938Y1207027D01*
X310403Y1207103D01*
X310713Y1207218D01*
X311023Y1207448D01*
X311230Y1207717D01*
X311333Y1207985D01*
Y1208253D01*
X311230Y1208522D01*
X311075Y1208752D01*
X310868Y1208943D01*
G01Y1210242D02*
X311126Y1210472D01*
X311281Y1210740D01*
X311333Y1211085D01*
X311230Y1211430D01*
X311023Y1211698D01*
X310661Y1211890D01*
X310248Y1211928D01*
X309835Y1211852D01*
X309576Y1211660D01*
X309370Y1211392D01*
X309318Y1211123D01*
X309370Y1210855D01*
X309576Y1210510D01*
X308233Y1210625D01*
Y1211660D01*
G01X311333Y1214645D02*
X308233D01*
X310455Y1213227D01*
Y1215143D01*
G01X298052Y1209043D02*
X297897Y1208813D01*
X297794Y1208545D01*
Y1208238D01*
X297949Y1207893D01*
X298207Y1207625D01*
X298517Y1207433D01*
X299034Y1207280D01*
X299499Y1207242D01*
X299964Y1207318D01*
X300274Y1207433D01*
X300584Y1207663D01*
X300791Y1207932D01*
X300894Y1208200D01*
Y1208468D01*
X300791Y1208737D01*
X300636Y1208967D01*
X300429Y1209158D01*
G01Y1210457D02*
X300687Y1210687D01*
X300842Y1210955D01*
X300894Y1211300D01*
X300791Y1211645D01*
X300584Y1211913D01*
X300222Y1212105D01*
X299809Y1212143D01*
X299396Y1212067D01*
X299137Y1211875D01*
X298931Y1211607D01*
X298879Y1211338D01*
X298931Y1211070D01*
X299137Y1210725D01*
X297794Y1210840D01*
Y1211875D01*
G01X299602Y1213672D02*
X299241Y1213940D01*
X299034Y1214170D01*
X298931Y1214477D01*
X299034Y1214745D01*
X299241Y1214937D01*
X299551Y1215090D01*
X299912Y1215128D01*
X300222Y1215090D01*
X300532Y1214937D01*
X300791Y1214707D01*
X300894Y1214438D01*
X300791Y1214132D01*
X300481Y1213863D01*
X300016Y1213710D01*
X299499Y1213672D01*
X298827Y1213748D01*
X298466Y1213863D01*
X298104Y1214055D01*
X297846Y1214323D01*
X297794Y1214592D01*
X297897Y1214860D01*
X298156Y1215052D01*
G01X292633Y1285522D02*
X295633D01*
G01X295733Y1288622D02*
Y1282422D01*
X292533D01*
Y1288622D01*
X295733D01*
G01X292460Y1298351D02*
X292305Y1298121D01*
X292202Y1297853D01*
Y1297546D01*
X292357Y1297201D01*
X292615Y1296933D01*
X292925Y1296741D01*
X293442Y1296588D01*
X293907Y1296550D01*
X294372Y1296626D01*
X294682Y1296741D01*
X294992Y1296971D01*
X295199Y1297240D01*
X295302Y1297508D01*
Y1297776D01*
X295199Y1298045D01*
X295044Y1298275D01*
X294837Y1298466D01*
G01Y1299765D02*
X295095Y1299995D01*
X295250Y1300263D01*
X295302Y1300608D01*
X295199Y1300953D01*
X294992Y1301221D01*
X294630Y1301413D01*
X294217Y1301451D01*
X293804Y1301375D01*
X293545Y1301183D01*
X293339Y1300915D01*
X293287Y1300646D01*
X293339Y1300378D01*
X293545Y1300033D01*
X292202Y1300148D01*
Y1301183D01*
G01X292719Y1302980D02*
X292409Y1303210D01*
X292254Y1303478D01*
X292202Y1303785D01*
X292305Y1304168D01*
X292564Y1304436D01*
X292874Y1304513D01*
X293184Y1304475D01*
X293442Y1304321D01*
X293959Y1303555D01*
X294320Y1303210D01*
X294837Y1302980D01*
X295302Y1302903D01*
Y1304513D01*
G01X304216Y1527637D02*
Y1530737D01*
X305175D01*
X305481Y1530582D01*
X305673Y1530375D01*
X305750Y1529962D01*
X305673Y1529549D01*
X305443Y1529290D01*
X305175Y1529135D01*
X304216D01*
G01X305175D02*
X305750Y1527637D01*
G01X308083D02*
Y1530737D01*
X307623Y1530117D01*
G01Y1527637D02*
X308543D01*
G01X310455Y1530220D02*
X310685Y1530530D01*
X310953Y1530685D01*
X311260Y1530737D01*
X311643Y1530634D01*
X311911Y1530375D01*
X311988Y1530065D01*
X311950Y1529755D01*
X311796Y1529497D01*
X311030Y1528980D01*
X310685Y1528619D01*
X310455Y1528102D01*
X310378Y1527637D01*
X311988D01*
G01X314206D02*
X314283Y1528309D01*
X314398Y1528877D01*
X314551Y1529394D01*
X314743Y1529962D01*
X315050Y1530737D01*
X313516D01*
G01X310431Y1522801D02*
X304231D01*
Y1526001D01*
X310431D01*
Y1522801D01*
G01X302996Y1507074D02*
Y1510174D01*
X303955D01*
X304261Y1510019D01*
X304453Y1509812D01*
X304530Y1509399D01*
X304453Y1508986D01*
X304223Y1508727D01*
X303955Y1508572D01*
X302996D01*
G01X303955D02*
X304530Y1507074D01*
G01X306863D02*
Y1510174D01*
X306403Y1509554D01*
G01Y1507074D02*
X307323D01*
G01X309235Y1509657D02*
X309465Y1509967D01*
X309733Y1510122D01*
X310040Y1510174D01*
X310423Y1510071D01*
X310691Y1509812D01*
X310768Y1509502D01*
X310730Y1509192D01*
X310576Y1508934D01*
X309810Y1508417D01*
X309465Y1508056D01*
X309235Y1507539D01*
X309158Y1507074D01*
X310768D01*
G01X313063D02*
X313331Y1507126D01*
X313638Y1507281D01*
X313830Y1507539D01*
X313906Y1507901D01*
X313830Y1508262D01*
X313600Y1508572D01*
X313255Y1508727D01*
X312871D01*
X312641Y1508831D01*
X312450Y1509089D01*
X312373Y1509451D01*
X312488Y1509812D01*
X312756Y1510071D01*
X313063Y1510174D01*
X313370Y1510071D01*
X313638Y1509812D01*
X313753Y1509451D01*
X313676Y1509089D01*
X313485Y1508831D01*
X313255Y1508727D01*
X312871D01*
X312526Y1508572D01*
X312296Y1508262D01*
X312220Y1507901D01*
X312296Y1507539D01*
X312488Y1507281D01*
X312795Y1507126D01*
X313063Y1507074D01*
G01X310161Y1512283D02*
X303961D01*
Y1515483D01*
X310161D01*
Y1512283D01*
G01X300370Y1564026D02*
X297370D01*
G01X297270Y1560926D02*
Y1567126D01*
X300470D01*
Y1560926D01*
X297270D01*
G01X295892Y1564026D02*
X292892D01*
G01X292792Y1560926D02*
Y1567126D01*
X295992D01*
Y1560926D01*
X292792D01*
G01X292439Y1649549D02*
X292284Y1649319D01*
X292181Y1649051D01*
Y1648744D01*
X292336Y1648399D01*
X292594Y1648131D01*
X292904Y1647939D01*
X293421Y1647786D01*
X293886Y1647748D01*
X294351Y1647824D01*
X294661Y1647939D01*
X294971Y1648169D01*
X295178Y1648438D01*
X295281Y1648706D01*
Y1648974D01*
X295178Y1649243D01*
X295023Y1649473D01*
X294816Y1649664D01*
G01X293989Y1651078D02*
X293628Y1651346D01*
X293421Y1651576D01*
X293318Y1651883D01*
X293421Y1652151D01*
X293628Y1652343D01*
X293938Y1652496D01*
X294299Y1652534D01*
X294609Y1652496D01*
X294919Y1652343D01*
X295178Y1652113D01*
X295281Y1651844D01*
X295178Y1651538D01*
X294868Y1651269D01*
X294403Y1651116D01*
X293886Y1651078D01*
X293214Y1651154D01*
X292853Y1651269D01*
X292491Y1651461D01*
X292233Y1651729D01*
X292181Y1651998D01*
X292284Y1652266D01*
X292543Y1652458D01*
G01X293989Y1654178D02*
X293628Y1654446D01*
X293421Y1654676D01*
X293318Y1654983D01*
X293421Y1655251D01*
X293628Y1655443D01*
X293938Y1655596D01*
X294299Y1655634D01*
X294609Y1655596D01*
X294919Y1655443D01*
X295178Y1655213D01*
X295281Y1654944D01*
X295178Y1654638D01*
X294868Y1654369D01*
X294403Y1654216D01*
X293886Y1654178D01*
X293214Y1654254D01*
X292853Y1654369D01*
X292491Y1654561D01*
X292233Y1654829D01*
X292181Y1655098D01*
X292284Y1655366D01*
X292543Y1655558D01*
G01X292590Y1635743D02*
X295590D01*
G01X295690Y1638843D02*
Y1632643D01*
X292490D01*
Y1638843D01*
X295690D01*
G01X291465Y1823628D02*
X291310Y1823398D01*
X291207Y1823130D01*
Y1822823D01*
X291362Y1822478D01*
X291620Y1822210D01*
X291930Y1822018D01*
X292447Y1821865D01*
X292912Y1821827D01*
X293377Y1821903D01*
X293687Y1822018D01*
X293997Y1822248D01*
X294204Y1822517D01*
X294307Y1822785D01*
Y1823053D01*
X294204Y1823322D01*
X294049Y1823552D01*
X293842Y1823743D01*
G01X294307Y1825808D02*
X293635Y1825885D01*
X293067Y1826000D01*
X292550Y1826153D01*
X291982Y1826345D01*
X291207Y1826652D01*
Y1825118D01*
G01X293687Y1828142D02*
X294049Y1828372D01*
X294255Y1828678D01*
X294307Y1829023D01*
X294255Y1829330D01*
X293997Y1829637D01*
X293687Y1829828D01*
X293377Y1829867D01*
X293015Y1829790D01*
X292757Y1829522D01*
X292654Y1829253D01*
Y1828908D01*
G01Y1829253D02*
X292499Y1829483D01*
X292240Y1829675D01*
X291930Y1829752D01*
X291620Y1829675D01*
X291362Y1829483D01*
X291207Y1829138D01*
X291259Y1828793D01*
X291465Y1828448D01*
G01X293636Y1883071D02*
Y1885021D01*
G02X307086Y1898471I13450J0D01*
G02X320536Y1885021I0J-13450D01*
G01Y1881121D01*
G02X307086Y1867671I-13450J0D01*
G02X293636Y1881121I0J13450D01*
G01Y1883071D01*
G01X316862Y1991607D02*
Y1981407D01*
X312262D01*
Y1991607D01*
X316862D01*
G01Y1986507D02*
X312262D01*
G01X313092Y1998233D02*
X312937Y1998003D01*
X312834Y1997735D01*
Y1997428D01*
X312989Y1997083D01*
X313247Y1996815D01*
X313557Y1996623D01*
X314074Y1996470D01*
X314539Y1996432D01*
X315004Y1996508D01*
X315314Y1996623D01*
X315624Y1996853D01*
X315831Y1997122D01*
X315934Y1997390D01*
Y1997658D01*
X315831Y1997927D01*
X315676Y1998157D01*
X315469Y1998348D01*
G01X315934Y2000413D02*
X315262Y2000490D01*
X314694Y2000605D01*
X314177Y2000758D01*
X313609Y2000950D01*
X312834Y2001257D01*
Y1999723D01*
G01X315934Y2003590D02*
X315882Y2003858D01*
X315727Y2004165D01*
X315469Y2004357D01*
X315107Y2004433D01*
X314746Y2004357D01*
X314436Y2004127D01*
X314281Y2003782D01*
Y2003398D01*
X314177Y2003168D01*
X313919Y2002977D01*
X313557Y2002900D01*
X313196Y2003015D01*
X312937Y2003283D01*
X312834Y2003590D01*
X312937Y2003897D01*
X313196Y2004165D01*
X313557Y2004280D01*
X313919Y2004203D01*
X314177Y2004012D01*
X314281Y2003782D01*
Y2003398D01*
X314436Y2003053D01*
X314746Y2002823D01*
X315107Y2002747D01*
X315469Y2002823D01*
X315727Y2003015D01*
X315882Y2003322D01*
X315934Y2003590D01*
G01X328600Y-123333D02*
X329200Y-122533D01*
X329900Y-122133D01*
X330700Y-122000D01*
X331700Y-122267D01*
X332400Y-122933D01*
X332600Y-123733D01*
X332500Y-124534D01*
X332100Y-125200D01*
X330100Y-126533D01*
X329200Y-127467D01*
X328600Y-128800D01*
X328400Y-130000D01*
X332600D01*
G01X338500Y-122000D02*
X337700Y-122267D01*
X337100Y-122933D01*
X336700Y-123733D01*
X336400Y-124800D01*
X336300Y-126000D01*
X336400Y-127200D01*
X336700Y-128267D01*
X337100Y-129067D01*
X337700Y-129733D01*
X338500Y-130000D01*
X339300Y-129733D01*
X339900Y-129067D01*
X340300Y-128267D01*
X340600Y-127200D01*
X340700Y-126000D01*
X340600Y-124800D01*
X340300Y-123733D01*
X339900Y-122933D01*
X339300Y-122267D01*
X338500Y-122000D01*
G01X346500Y-130000D02*
Y-122000D01*
X345300Y-123600D01*
G01Y-130000D02*
X347700D01*
G01X352600Y-123333D02*
X353200Y-122533D01*
X353900Y-122133D01*
X354700Y-122000D01*
X355700Y-122267D01*
X356400Y-122933D01*
X356600Y-123733D01*
X356500Y-124534D01*
X356100Y-125200D01*
X354100Y-126533D01*
X353200Y-127467D01*
X352600Y-128800D01*
X352400Y-130000D01*
X356600D01*
G01X360700Y-130267D02*
X364300Y-122000D01*
G01X370500D02*
X369700Y-122267D01*
X369100Y-122933D01*
X368700Y-123733D01*
X368400Y-124800D01*
X368300Y-126000D01*
X368400Y-127200D01*
X368700Y-128267D01*
X369100Y-129067D01*
X369700Y-129733D01*
X370500Y-130000D01*
X371300Y-129733D01*
X371900Y-129067D01*
X372300Y-128267D01*
X372600Y-127200D01*
X372700Y-126000D01*
X372600Y-124800D01*
X372300Y-123733D01*
X371900Y-122933D01*
X371300Y-122267D01*
X370500Y-122000D01*
G01X376800Y-129067D02*
X377500Y-129733D01*
X378300Y-130000D01*
X379100Y-129733D01*
X379800Y-128934D01*
X380300Y-127733D01*
X380500Y-126533D01*
Y-125067D01*
X380300Y-123867D01*
X379800Y-122800D01*
X379200Y-122267D01*
X378500Y-122000D01*
X377700Y-122267D01*
X377100Y-122800D01*
X376700Y-123600D01*
X376500Y-124667D01*
X376700Y-125600D01*
X377200Y-126533D01*
X377800Y-127067D01*
X378500Y-127200D01*
X379300Y-126934D01*
X379900Y-126267D01*
X380500Y-125067D01*
G01X384700Y-130267D02*
X388300Y-122000D01*
G01X392600Y-123333D02*
X393200Y-122533D01*
X393900Y-122133D01*
X394700Y-122000D01*
X395700Y-122267D01*
X396400Y-122933D01*
X396600Y-123733D01*
X396500Y-124534D01*
X396100Y-125200D01*
X394100Y-126533D01*
X393200Y-127467D01*
X392600Y-128800D01*
X392400Y-130000D01*
X396600D01*
G01X402500D02*
X403200Y-129867D01*
X404000Y-129467D01*
X404500Y-128800D01*
X404700Y-127867D01*
X404500Y-126934D01*
X403900Y-126133D01*
X403000Y-125733D01*
X402000D01*
X401400Y-125467D01*
X400900Y-124800D01*
X400700Y-123867D01*
X401000Y-122933D01*
X401700Y-122267D01*
X402500Y-122000D01*
X403300Y-122267D01*
X404000Y-122933D01*
X404300Y-123867D01*
X404100Y-124800D01*
X403600Y-125467D01*
X403000Y-125733D01*
X402000D01*
X401100Y-126133D01*
X400500Y-126934D01*
X400300Y-127867D01*
X400500Y-128800D01*
X401000Y-129467D01*
X401800Y-129867D01*
X402500Y-130000D01*
G01X328300Y-105000D02*
Y-97000D01*
X330300D01*
X331100Y-97400D01*
X331700Y-97933D01*
X332200Y-98733D01*
X332600Y-99667D01*
X332700Y-101000D01*
X332600Y-102333D01*
X332200Y-103267D01*
X331700Y-104067D01*
X331100Y-104600D01*
X330300Y-105000D01*
X328300D01*
G01X336000D02*
X338500Y-97000D01*
X341000Y-105000D01*
G01X340100Y-102200D02*
X336900D01*
G01X346500Y-97000D02*
X345700Y-97267D01*
X345100Y-97933D01*
X344700Y-98733D01*
X344400Y-99800D01*
X344300Y-101000D01*
X344400Y-102200D01*
X344700Y-103267D01*
X345100Y-104067D01*
X345700Y-104733D01*
X346500Y-105000D01*
X347300Y-104733D01*
X347900Y-104067D01*
X348300Y-103267D01*
X348600Y-102200D01*
X348700Y-101000D01*
X348600Y-99800D01*
X348300Y-98733D01*
X347900Y-97933D01*
X347300Y-97267D01*
X346500Y-97000D01*
G01X354500D02*
Y-105000D01*
G01X352200Y-97000D02*
X356800D01*
G01X360600Y-101667D02*
X361300Y-100733D01*
X361900Y-100200D01*
X362700Y-99933D01*
X363400Y-100200D01*
X363900Y-100733D01*
X364300Y-101533D01*
X364400Y-102467D01*
X364300Y-103267D01*
X363900Y-104067D01*
X363300Y-104733D01*
X362600Y-105000D01*
X361800Y-104733D01*
X361100Y-103934D01*
X360700Y-102733D01*
X360600Y-101400D01*
X360800Y-99667D01*
X361100Y-98733D01*
X361600Y-97800D01*
X362300Y-97133D01*
X363000Y-97000D01*
X363700Y-97267D01*
X364200Y-97933D01*
G01X367900Y-105000D02*
Y-97000D01*
X370500Y-103667D01*
X373100Y-97000D01*
Y-105000D01*
G01X378500Y-97000D02*
Y-105000D01*
G01X376200Y-97000D02*
X380800D01*
G01X387300Y-100733D02*
X387700Y-100333D01*
X388000Y-99667D01*
X388200Y-98733D01*
X388000Y-97933D01*
X387600Y-97400D01*
X386900Y-97000D01*
X384200D01*
Y-105000D01*
X387500D01*
X388200Y-104467D01*
X388600Y-103667D01*
X388800Y-102733D01*
X388600Y-101800D01*
X388000Y-101000D01*
X387300Y-100733D01*
X384200D01*
G01X394500Y-105000D02*
X395200Y-104867D01*
X396000Y-104467D01*
X396500Y-103800D01*
X396700Y-102867D01*
X396500Y-101934D01*
X395900Y-101133D01*
X395000Y-100733D01*
X394000D01*
X393400Y-100467D01*
X392900Y-99800D01*
X392700Y-98867D01*
X393000Y-97933D01*
X393700Y-97267D01*
X394500Y-97000D01*
X395300Y-97267D01*
X396000Y-97933D01*
X396300Y-98867D01*
X396100Y-99800D01*
X395600Y-100467D01*
X395000Y-100733D01*
X394000D01*
X393100Y-101133D01*
X392500Y-101934D01*
X392300Y-102867D01*
X392500Y-103800D01*
X393000Y-104467D01*
X393800Y-104867D01*
X394500Y-105000D01*
G01X400300D02*
Y-97000D01*
X402300D01*
X403100Y-97400D01*
X403700Y-97933D01*
X404200Y-98733D01*
X404600Y-99667D01*
X404700Y-101000D01*
X404600Y-102333D01*
X404200Y-103267D01*
X403700Y-104067D01*
X403100Y-104600D01*
X402300Y-105000D01*
X400300D01*
G01X410500Y-97000D02*
X409700Y-97267D01*
X409100Y-97933D01*
X408700Y-98733D01*
X408400Y-99800D01*
X408300Y-101000D01*
X408400Y-102200D01*
X408700Y-103267D01*
X409100Y-104067D01*
X409700Y-104733D01*
X410500Y-105000D01*
X411300Y-104733D01*
X411900Y-104067D01*
X412300Y-103267D01*
X412600Y-102200D01*
X412700Y-101000D01*
X412600Y-99800D01*
X412300Y-98733D01*
X411900Y-97933D01*
X411300Y-97267D01*
X410500Y-97000D01*
G01X318760Y14273D02*
Y17373D01*
X319680D01*
X319987Y17218D01*
X320217Y16856D01*
X320294Y16443D01*
X320217Y16030D01*
X320025Y15720D01*
X319680Y15565D01*
X318760D01*
G01X322627Y14273D02*
Y17373D01*
X322167Y16753D01*
G01Y14273D02*
X323087D01*
G01X325650D02*
X325727Y14945D01*
X325842Y15513D01*
X325995Y16030D01*
X326187Y16598D01*
X326494Y17373D01*
X324960D01*
G01X331842Y14000D02*
X332149Y13742D01*
X332494Y13587D01*
X332800D01*
X333107Y13742D01*
X333337Y14000D01*
X333452Y14362D01*
X333375Y14724D01*
X333184Y15034D01*
X332839Y15240D01*
X332379Y15344D01*
X332110Y15550D01*
X331995Y15912D01*
X332072Y16274D01*
X332264Y16532D01*
X332532Y16687D01*
X332800D01*
X333069Y16584D01*
X333299Y16325D01*
G01X335747Y13587D02*
Y16687D01*
X335287Y16067D01*
G01Y13587D02*
X336207D01*
G01X338119Y16170D02*
X338349Y16480D01*
X338617Y16635D01*
X338924Y16687D01*
X339307Y16584D01*
X339575Y16325D01*
X339652Y16015D01*
X339614Y15705D01*
X339460Y15447D01*
X338694Y14930D01*
X338349Y14569D01*
X338119Y14052D01*
X338042Y13587D01*
X339652D01*
G01X319167Y61918D02*
Y55718D01*
X315967D01*
Y61918D01*
X319167D01*
G01X323605D02*
Y55718D01*
X320405D01*
Y61918D01*
X323605D01*
G01X318930Y36708D02*
Y39808D01*
X319850D01*
X320157Y39653D01*
X320387Y39291D01*
X320464Y38878D01*
X320387Y38465D01*
X320195Y38155D01*
X319850Y38000D01*
X318930D01*
G01X322797Y36708D02*
Y39808D01*
X322337Y39188D01*
G01Y36708D02*
X323257D01*
G01X325169Y38000D02*
X325437Y38361D01*
X325667Y38568D01*
X325974Y38671D01*
X326242Y38568D01*
X326434Y38361D01*
X326587Y38051D01*
X326625Y37690D01*
X326587Y37380D01*
X326434Y37070D01*
X326204Y36811D01*
X325935Y36708D01*
X325629Y36811D01*
X325360Y37121D01*
X325207Y37586D01*
X325169Y38103D01*
X325245Y38775D01*
X325360Y39136D01*
X325552Y39498D01*
X325820Y39756D01*
X326089Y39808D01*
X326357Y39705D01*
X326549Y39446D01*
G01X334892Y39650D02*
X335199Y39392D01*
X335544Y39237D01*
X335850D01*
X336157Y39392D01*
X336387Y39650D01*
X336502Y40012D01*
X336425Y40374D01*
X336234Y40684D01*
X335889Y40890D01*
X335429Y40994D01*
X335160Y41200D01*
X335045Y41562D01*
X335122Y41924D01*
X335314Y42182D01*
X335582Y42337D01*
X335850D01*
X336119Y42234D01*
X336349Y41975D01*
G01X338797Y39237D02*
Y42337D01*
X338337Y41717D01*
G01Y39237D02*
X339257D01*
G01X316046Y67706D02*
X315891Y67476D01*
X315788Y67208D01*
Y66901D01*
X315943Y66556D01*
X316201Y66288D01*
X316511Y66096D01*
X317028Y65943D01*
X317493Y65905D01*
X317958Y65981D01*
X318268Y66096D01*
X318578Y66326D01*
X318785Y66595D01*
X318888Y66863D01*
Y67131D01*
X318785Y67400D01*
X318630Y67630D01*
X318423Y67821D01*
G01X317596Y69235D02*
X317235Y69503D01*
X317028Y69733D01*
X316925Y70040D01*
X317028Y70308D01*
X317235Y70500D01*
X317545Y70653D01*
X317906Y70691D01*
X318216Y70653D01*
X318526Y70500D01*
X318785Y70270D01*
X318888Y70001D01*
X318785Y69695D01*
X318475Y69426D01*
X318010Y69273D01*
X317493Y69235D01*
X316821Y69311D01*
X316460Y69426D01*
X316098Y69618D01*
X315840Y69886D01*
X315788Y70155D01*
X315891Y70423D01*
X316150Y70615D01*
G01X316067Y58818D02*
X319067D01*
G01X320927Y67706D02*
X320772Y67476D01*
X320669Y67208D01*
Y66901D01*
X320824Y66556D01*
X321082Y66288D01*
X321392Y66096D01*
X321909Y65943D01*
X322374Y65905D01*
X322839Y65981D01*
X323149Y66096D01*
X323459Y66326D01*
X323666Y66595D01*
X323769Y66863D01*
Y67131D01*
X323666Y67400D01*
X323511Y67630D01*
X323304Y67821D01*
G01X323769Y69886D02*
X323097Y69963D01*
X322529Y70078D01*
X322012Y70231D01*
X321444Y70423D01*
X320669Y70730D01*
Y69196D01*
G01X320505Y58818D02*
X323505D01*
G01X335667Y151259D02*
Y154359D01*
G01X337277D02*
Y151259D01*
G01Y152809D02*
X335667D01*
G01X339572Y151259D02*
Y154359D01*
X339112Y153739D01*
G01Y151259D02*
X340032D01*
G01X341944Y153842D02*
X342174Y154152D01*
X342442Y154307D01*
X342749Y154359D01*
X343132Y154256D01*
X343400Y153997D01*
X343477Y153687D01*
X343439Y153377D01*
X343285Y153119D01*
X342519Y152602D01*
X342174Y152241D01*
X341944Y151724D01*
X341867Y151259D01*
X343477D01*
G01X318706Y171275D02*
Y174375D01*
X319626D01*
X319933Y174220D01*
X320163Y173858D01*
X320240Y173445D01*
X320163Y173032D01*
X319971Y172722D01*
X319626Y172567D01*
X318706D01*
G01X322573Y171275D02*
Y174375D01*
X322113Y173755D01*
G01Y171275D02*
X323033D01*
G01X325596D02*
X325673Y171947D01*
X325788Y172515D01*
X325941Y173032D01*
X326133Y173600D01*
X326440Y174375D01*
X324906D01*
G01X334851Y171293D02*
X335158Y171035D01*
X335503Y170880D01*
X335809D01*
X336116Y171035D01*
X336346Y171293D01*
X336461Y171655D01*
X336384Y172017D01*
X336193Y172327D01*
X335848Y172533D01*
X335388Y172637D01*
X335119Y172843D01*
X335004Y173205D01*
X335081Y173567D01*
X335273Y173825D01*
X335541Y173980D01*
X335809D01*
X336078Y173877D01*
X336308Y173618D01*
G01X338756Y170880D02*
Y173980D01*
X338296Y173360D01*
G01Y170880D02*
X339216D01*
G01X341128Y173463D02*
X341358Y173773D01*
X341626Y173928D01*
X341933Y173980D01*
X342316Y173877D01*
X342584Y173618D01*
X342661Y173308D01*
X342623Y172998D01*
X342469Y172740D01*
X341703Y172223D01*
X341358Y171862D01*
X341128Y171345D01*
X341051Y170880D01*
X342661D01*
G01X322258Y233377D02*
Y236477D01*
X323178D01*
X323485Y236322D01*
X323715Y235960D01*
X323792Y235547D01*
X323715Y235134D01*
X323523Y234824D01*
X323178Y234669D01*
X322258D01*
G01X326125Y233377D02*
Y236477D01*
X325665Y235857D01*
G01Y233377D02*
X326585D01*
G01X328497Y234669D02*
X328765Y235030D01*
X328995Y235237D01*
X329302Y235340D01*
X329570Y235237D01*
X329762Y235030D01*
X329915Y234720D01*
X329953Y234359D01*
X329915Y234049D01*
X329762Y233739D01*
X329532Y233480D01*
X329263Y233377D01*
X328957Y233480D01*
X328688Y233790D01*
X328535Y234255D01*
X328497Y234772D01*
X328573Y235444D01*
X328688Y235805D01*
X328880Y236167D01*
X329148Y236425D01*
X329417Y236477D01*
X329685Y236374D01*
X329877Y236115D01*
G01X335826Y231425D02*
X336133Y231167D01*
X336478Y231012D01*
X336784D01*
X337091Y231167D01*
X337321Y231425D01*
X337436Y231787D01*
X337359Y232149D01*
X337168Y232459D01*
X336823Y232665D01*
X336363Y232769D01*
X336094Y232975D01*
X335979Y233337D01*
X336056Y233699D01*
X336248Y233957D01*
X336516Y234112D01*
X336784D01*
X337053Y234009D01*
X337283Y233750D01*
G01X339731Y231012D02*
Y234112D01*
X339271Y233492D01*
G01Y231012D02*
X340191D01*
G01X320474Y346510D02*
Y349610D01*
X321394D01*
X321701Y349455D01*
X321931Y349093D01*
X322008Y348680D01*
X321931Y348267D01*
X321739Y347957D01*
X321394Y347802D01*
X320474D01*
G01X324341Y346510D02*
Y349610D01*
X323881Y348990D01*
G01Y346510D02*
X324801D01*
G01X327364D02*
X327441Y347182D01*
X327556Y347750D01*
X327709Y348267D01*
X327901Y348835D01*
X328208Y349610D01*
X326674D01*
G01X333758Y345232D02*
X334065Y344974D01*
X334410Y344819D01*
X334716D01*
X335023Y344974D01*
X335253Y345232D01*
X335368Y345594D01*
X335291Y345956D01*
X335100Y346266D01*
X334755Y346472D01*
X334295Y346576D01*
X334026Y346782D01*
X333911Y347144D01*
X333988Y347506D01*
X334180Y347764D01*
X334448Y347919D01*
X334716D01*
X334985Y347816D01*
X335215Y347557D01*
G01X337663Y344819D02*
Y347919D01*
X337203Y347299D01*
G01Y344819D02*
X338123D01*
G01X340035Y347402D02*
X340265Y347712D01*
X340533Y347867D01*
X340840Y347919D01*
X341223Y347816D01*
X341491Y347557D01*
X341568Y347247D01*
X341530Y346937D01*
X341376Y346679D01*
X340610Y346162D01*
X340265Y345801D01*
X340035Y345284D01*
X339958Y344819D01*
X341568D01*
G01X318429Y408605D02*
Y411705D01*
X319349D01*
X319656Y411550D01*
X319886Y411188D01*
X319963Y410775D01*
X319886Y410362D01*
X319694Y410052D01*
X319349Y409897D01*
X318429D01*
G01X322296Y408605D02*
Y411705D01*
X321836Y411085D01*
G01Y408605D02*
X322756D01*
G01X324668Y409897D02*
X324936Y410258D01*
X325166Y410465D01*
X325473Y410568D01*
X325741Y410465D01*
X325933Y410258D01*
X326086Y409948D01*
X326124Y409587D01*
X326086Y409277D01*
X325933Y408967D01*
X325703Y408708D01*
X325434Y408605D01*
X325128Y408708D01*
X324859Y409018D01*
X324706Y409483D01*
X324668Y410000D01*
X324744Y410672D01*
X324859Y411033D01*
X325051Y411395D01*
X325319Y411653D01*
X325588Y411705D01*
X325856Y411602D01*
X326048Y411343D01*
G01X334843Y406941D02*
X335150Y406683D01*
X335495Y406528D01*
X335801D01*
X336108Y406683D01*
X336338Y406941D01*
X336453Y407303D01*
X336376Y407665D01*
X336185Y407975D01*
X335840Y408181D01*
X335380Y408285D01*
X335111Y408491D01*
X334996Y408853D01*
X335073Y409215D01*
X335265Y409473D01*
X335533Y409628D01*
X335801D01*
X336070Y409525D01*
X336300Y409266D01*
G01X338748Y406528D02*
Y409628D01*
X338288Y409008D01*
G01Y406528D02*
X339208D01*
G01X327785Y518623D02*
Y521723D01*
X328705D01*
X329012Y521568D01*
X329242Y521206D01*
X329319Y520793D01*
X329242Y520380D01*
X329050Y520070D01*
X328705Y519915D01*
X327785D01*
G01X331652Y518623D02*
Y521723D01*
X331192Y521103D01*
G01Y518623D02*
X332112D01*
G01X334675D02*
X334752Y519295D01*
X334867Y519863D01*
X335020Y520380D01*
X335212Y520948D01*
X335519Y521723D01*
X333985D01*
G01X338404Y521009D02*
X338711Y520751D01*
X339056Y520596D01*
X339362D01*
X339669Y520751D01*
X339899Y521009D01*
X340014Y521371D01*
X339937Y521733D01*
X339746Y522043D01*
X339401Y522249D01*
X338941Y522353D01*
X338672Y522559D01*
X338557Y522921D01*
X338634Y523283D01*
X338826Y523541D01*
X339094Y523696D01*
X339362D01*
X339631Y523593D01*
X339861Y523334D01*
G01X342309Y520596D02*
Y523696D01*
X341849Y523076D01*
G01Y520596D02*
X342769D01*
G01X344681Y523179D02*
X344911Y523489D01*
X345179Y523644D01*
X345486Y523696D01*
X345869Y523593D01*
X346137Y523334D01*
X346214Y523024D01*
X346176Y522714D01*
X346022Y522456D01*
X345256Y521939D01*
X344911Y521578D01*
X344681Y521061D01*
X344604Y520596D01*
X346214D01*
G01X318311Y579671D02*
Y582771D01*
X319231D01*
X319538Y582616D01*
X319768Y582254D01*
X319845Y581841D01*
X319768Y581428D01*
X319576Y581118D01*
X319231Y580963D01*
X318311D01*
G01X322178Y579671D02*
Y582771D01*
X321718Y582151D01*
G01Y579671D02*
X322638D01*
G01X324550Y580963D02*
X324818Y581324D01*
X325048Y581531D01*
X325355Y581634D01*
X325623Y581531D01*
X325815Y581324D01*
X325968Y581014D01*
X326006Y580653D01*
X325968Y580343D01*
X325815Y580033D01*
X325585Y579774D01*
X325316Y579671D01*
X325010Y579774D01*
X324741Y580084D01*
X324588Y580549D01*
X324550Y581066D01*
X324626Y581738D01*
X324741Y582099D01*
X324933Y582461D01*
X325201Y582719D01*
X325470Y582771D01*
X325738Y582668D01*
X325930Y582409D01*
G01X334652Y582055D02*
X334959Y581797D01*
X335304Y581642D01*
X335610D01*
X335917Y581797D01*
X336147Y582055D01*
X336262Y582417D01*
X336185Y582779D01*
X335994Y583089D01*
X335649Y583295D01*
X335189Y583399D01*
X334920Y583605D01*
X334805Y583967D01*
X334882Y584329D01*
X335074Y584587D01*
X335342Y584742D01*
X335610D01*
X335879Y584639D01*
X336109Y584380D01*
G01X338557Y581642D02*
Y584742D01*
X338097Y584122D01*
G01Y581642D02*
X339017D01*
G01X318731Y693559D02*
Y696659D01*
X319651D01*
X319958Y696504D01*
X320188Y696142D01*
X320265Y695729D01*
X320188Y695316D01*
X319996Y695006D01*
X319651Y694851D01*
X318731D01*
G01X322598Y693559D02*
Y696659D01*
X322138Y696039D01*
G01Y693559D02*
X323058D01*
G01X325621D02*
X325698Y694231D01*
X325813Y694799D01*
X325966Y695316D01*
X326158Y695884D01*
X326465Y696659D01*
X324931D01*
G01X328547Y696690D02*
X328854Y696432D01*
X329199Y696277D01*
X329505D01*
X329812Y696432D01*
X330042Y696690D01*
X330157Y697052D01*
X330080Y697414D01*
X329889Y697724D01*
X329544Y697930D01*
X329084Y698034D01*
X328815Y698240D01*
X328700Y698602D01*
X328777Y698964D01*
X328969Y699222D01*
X329237Y699377D01*
X329505D01*
X329774Y699274D01*
X330004Y699015D01*
G01X332452Y696277D02*
Y699377D01*
X331992Y698757D01*
G01Y696277D02*
X332912D01*
G01X334824Y698860D02*
X335054Y699170D01*
X335322Y699325D01*
X335629Y699377D01*
X336012Y699274D01*
X336280Y699015D01*
X336357Y698705D01*
X336319Y698395D01*
X336165Y698137D01*
X335399Y697620D01*
X335054Y697259D01*
X334824Y696742D01*
X334747Y696277D01*
X336357D01*
G01X317016Y755587D02*
Y758687D01*
X317936D01*
X318243Y758532D01*
X318473Y758170D01*
X318550Y757757D01*
X318473Y757344D01*
X318281Y757034D01*
X317936Y756879D01*
X317016D01*
G01X320883Y755587D02*
Y758687D01*
X320423Y758067D01*
G01Y755587D02*
X321343D01*
G01X323255Y756879D02*
X323523Y757240D01*
X323753Y757447D01*
X324060Y757550D01*
X324328Y757447D01*
X324520Y757240D01*
X324673Y756930D01*
X324711Y756569D01*
X324673Y756259D01*
X324520Y755949D01*
X324290Y755690D01*
X324021Y755587D01*
X323715Y755690D01*
X323446Y756000D01*
X323293Y756465D01*
X323255Y756982D01*
X323331Y757654D01*
X323446Y758015D01*
X323638Y758377D01*
X323906Y758635D01*
X324175Y758687D01*
X324443Y758584D01*
X324635Y758325D01*
G01X335895Y756132D02*
X336202Y755874D01*
X336547Y755719D01*
X336853D01*
X337160Y755874D01*
X337390Y756132D01*
X337505Y756494D01*
X337428Y756856D01*
X337237Y757166D01*
X336892Y757372D01*
X336432Y757476D01*
X336163Y757682D01*
X336048Y758044D01*
X336125Y758406D01*
X336317Y758664D01*
X336585Y758819D01*
X336853D01*
X337122Y758716D01*
X337352Y758457D01*
G01X339800Y755719D02*
Y758819D01*
X339340Y758199D01*
G01Y755719D02*
X340260D01*
G01X318773Y870821D02*
Y873921D01*
X319693D01*
X320000Y873766D01*
X320230Y873404D01*
X320307Y872991D01*
X320230Y872578D01*
X320038Y872268D01*
X319693Y872113D01*
X318773D01*
G01X322640Y870821D02*
Y873921D01*
X322180Y873301D01*
G01Y870821D02*
X323100D01*
G01X325663D02*
X325740Y871493D01*
X325855Y872061D01*
X326008Y872578D01*
X326200Y873146D01*
X326507Y873921D01*
X324973D01*
G01X332256Y870816D02*
X332563Y870558D01*
X332908Y870403D01*
X333214D01*
X333521Y870558D01*
X333751Y870816D01*
X333866Y871178D01*
X333789Y871540D01*
X333598Y871850D01*
X333253Y872056D01*
X332793Y872160D01*
X332524Y872366D01*
X332409Y872728D01*
X332486Y873090D01*
X332678Y873348D01*
X332946Y873503D01*
X333214D01*
X333483Y873400D01*
X333713Y873141D01*
G01X336161Y870403D02*
Y873503D01*
X335701Y872883D01*
G01Y870403D02*
X336621D01*
G01X338533Y872986D02*
X338763Y873296D01*
X339031Y873451D01*
X339338Y873503D01*
X339721Y873400D01*
X339989Y873141D01*
X340066Y872831D01*
X340028Y872521D01*
X339874Y872263D01*
X339108Y871746D01*
X338763Y871385D01*
X338533Y870868D01*
X338456Y870403D01*
X340066D01*
G01X334448Y930858D02*
X334755Y930600D01*
X335100Y930445D01*
X335406D01*
X335713Y930600D01*
X335943Y930858D01*
X336058Y931220D01*
X335981Y931582D01*
X335790Y931892D01*
X335445Y932098D01*
X334985Y932202D01*
X334716Y932408D01*
X334601Y932770D01*
X334678Y933132D01*
X334870Y933390D01*
X335138Y933545D01*
X335406D01*
X335675Y933442D01*
X335905Y933183D01*
G01X338353Y930445D02*
Y933545D01*
X337893Y932925D01*
G01Y930445D02*
X338813D01*
G01X317127Y1045696D02*
Y1048796D01*
X318047D01*
X318354Y1048641D01*
X318584Y1048279D01*
X318661Y1047866D01*
X318584Y1047453D01*
X318392Y1047143D01*
X318047Y1046988D01*
X317127D01*
G01X320994Y1045696D02*
Y1048796D01*
X320534Y1048176D01*
G01Y1045696D02*
X321454D01*
G01X324017D02*
X324094Y1046368D01*
X324209Y1046936D01*
X324362Y1047453D01*
X324554Y1048021D01*
X324861Y1048796D01*
X323327D01*
G01X327088Y1045188D02*
X327395Y1044930D01*
X327740Y1044775D01*
X328046D01*
X328353Y1044930D01*
X328583Y1045188D01*
X328698Y1045550D01*
X328621Y1045912D01*
X328430Y1046222D01*
X328085Y1046428D01*
X327625Y1046532D01*
X327356Y1046738D01*
X327241Y1047100D01*
X327318Y1047462D01*
X327510Y1047720D01*
X327778Y1047875D01*
X328046D01*
X328315Y1047772D01*
X328545Y1047513D01*
G01X330993Y1044775D02*
Y1047875D01*
X330533Y1047255D01*
G01Y1044775D02*
X331453D01*
G01X333365Y1047358D02*
X333595Y1047668D01*
X333863Y1047823D01*
X334170Y1047875D01*
X334553Y1047772D01*
X334821Y1047513D01*
X334898Y1047203D01*
X334860Y1046893D01*
X334706Y1046635D01*
X333940Y1046118D01*
X333595Y1045757D01*
X333365Y1045240D01*
X333288Y1044775D01*
X334898D01*
G01X319882Y1105275D02*
Y1108375D01*
X320802D01*
X321109Y1108220D01*
X321339Y1107858D01*
X321416Y1107445D01*
X321339Y1107032D01*
X321147Y1106722D01*
X320802Y1106567D01*
X319882D01*
G01X323749Y1105275D02*
Y1108375D01*
X323289Y1107755D01*
G01Y1105275D02*
X324209D01*
G01X326121Y1106567D02*
X326389Y1106928D01*
X326619Y1107135D01*
X326926Y1107238D01*
X327194Y1107135D01*
X327386Y1106928D01*
X327539Y1106618D01*
X327577Y1106257D01*
X327539Y1105947D01*
X327386Y1105637D01*
X327156Y1105378D01*
X326887Y1105275D01*
X326581Y1105378D01*
X326312Y1105688D01*
X326159Y1106153D01*
X326121Y1106670D01*
X326197Y1107342D01*
X326312Y1107703D01*
X326504Y1108065D01*
X326772Y1108323D01*
X327041Y1108375D01*
X327309Y1108272D01*
X327501Y1108013D01*
G01X333506Y1105053D02*
X333813Y1104795D01*
X334158Y1104640D01*
X334464D01*
X334771Y1104795D01*
X335001Y1105053D01*
X335116Y1105415D01*
X335039Y1105777D01*
X334848Y1106087D01*
X334503Y1106293D01*
X334043Y1106397D01*
X333774Y1106603D01*
X333659Y1106965D01*
X333736Y1107327D01*
X333928Y1107585D01*
X334196Y1107740D01*
X334464D01*
X334733Y1107637D01*
X334963Y1107378D01*
G01X337411Y1104640D02*
Y1107740D01*
X336951Y1107120D01*
G01Y1104640D02*
X337871D01*
G01X321733Y1160666D02*
X315533D01*
Y1163866D01*
X321733D01*
Y1160666D01*
G01X321789Y1171204D02*
X315589D01*
Y1174404D01*
X321789D01*
Y1171204D01*
G01X317742Y1219580D02*
Y1222680D01*
X318662D01*
X318969Y1222525D01*
X319199Y1222163D01*
X319276Y1221750D01*
X319199Y1221337D01*
X319007Y1221027D01*
X318662Y1220872D01*
X317742D01*
G01X321609Y1219580D02*
Y1222680D01*
X321149Y1222060D01*
G01Y1219580D02*
X322069D01*
G01X324632D02*
X324709Y1220252D01*
X324824Y1220820D01*
X324977Y1221337D01*
X325169Y1221905D01*
X325476Y1222680D01*
X323942D01*
G01X330585Y1220931D02*
X330892Y1220673D01*
X331237Y1220518D01*
X331543D01*
X331850Y1220673D01*
X332080Y1220931D01*
X332195Y1221293D01*
X332118Y1221655D01*
X331927Y1221965D01*
X331582Y1222171D01*
X331122Y1222275D01*
X330853Y1222481D01*
X330738Y1222843D01*
X330815Y1223205D01*
X331007Y1223463D01*
X331275Y1223618D01*
X331543D01*
X331812Y1223515D01*
X332042Y1223256D01*
G01X334490Y1220518D02*
Y1223618D01*
X334030Y1222998D01*
G01Y1220518D02*
X334950D01*
G01X336862Y1223101D02*
X337092Y1223411D01*
X337360Y1223566D01*
X337667Y1223618D01*
X338050Y1223515D01*
X338318Y1223256D01*
X338395Y1222946D01*
X338357Y1222636D01*
X338203Y1222378D01*
X337437Y1221861D01*
X337092Y1221500D01*
X336862Y1220983D01*
X336785Y1220518D01*
X338395D01*
G01X319401Y1284348D02*
Y1287448D01*
X320321D01*
X320628Y1287293D01*
X320858Y1286931D01*
X320935Y1286518D01*
X320858Y1286105D01*
X320666Y1285795D01*
X320321Y1285640D01*
X319401D01*
G01X323268Y1284348D02*
Y1287448D01*
X322808Y1286828D01*
G01Y1284348D02*
X323728D01*
G01X325640Y1285640D02*
X325908Y1286001D01*
X326138Y1286208D01*
X326445Y1286311D01*
X326713Y1286208D01*
X326905Y1286001D01*
X327058Y1285691D01*
X327096Y1285330D01*
X327058Y1285020D01*
X326905Y1284710D01*
X326675Y1284451D01*
X326406Y1284348D01*
X326100Y1284451D01*
X325831Y1284761D01*
X325678Y1285226D01*
X325640Y1285743D01*
X325716Y1286415D01*
X325831Y1286776D01*
X326023Y1287138D01*
X326291Y1287396D01*
X326560Y1287448D01*
X326828Y1287345D01*
X327020Y1287086D01*
G01X335171Y1284761D02*
X335478Y1284503D01*
X335823Y1284348D01*
X336129D01*
X336436Y1284503D01*
X336666Y1284761D01*
X336781Y1285123D01*
X336704Y1285485D01*
X336513Y1285795D01*
X336168Y1286001D01*
X335708Y1286105D01*
X335439Y1286311D01*
X335324Y1286673D01*
X335401Y1287035D01*
X335593Y1287293D01*
X335861Y1287448D01*
X336129D01*
X336398Y1287345D01*
X336628Y1287086D01*
G01X339076Y1284348D02*
Y1287448D01*
X338616Y1286828D01*
G01Y1284348D02*
X339536D01*
G01X318713Y1394364D02*
Y1397464D01*
X319633D01*
X319940Y1397309D01*
X320170Y1396947D01*
X320247Y1396534D01*
X320170Y1396121D01*
X319978Y1395811D01*
X319633Y1395656D01*
X318713D01*
G01X322580Y1394364D02*
Y1397464D01*
X322120Y1396844D01*
G01Y1394364D02*
X323040D01*
G01X325603D02*
X325680Y1395036D01*
X325795Y1395604D01*
X325948Y1396121D01*
X326140Y1396689D01*
X326447Y1397464D01*
X324913D01*
G01X331265Y1395226D02*
X331572Y1394968D01*
X331917Y1394813D01*
X332223D01*
X332530Y1394968D01*
X332760Y1395226D01*
X332875Y1395588D01*
X332798Y1395950D01*
X332607Y1396260D01*
X332262Y1396466D01*
X331802Y1396570D01*
X331533Y1396776D01*
X331418Y1397138D01*
X331495Y1397500D01*
X331687Y1397758D01*
X331955Y1397913D01*
X332223D01*
X332492Y1397810D01*
X332722Y1397551D01*
G01X335170Y1394813D02*
Y1397913D01*
X334710Y1397293D01*
G01Y1394813D02*
X335630D01*
G01X337542Y1397396D02*
X337772Y1397706D01*
X338040Y1397861D01*
X338347Y1397913D01*
X338730Y1397810D01*
X338998Y1397551D01*
X339075Y1397241D01*
X339037Y1396931D01*
X338883Y1396673D01*
X338117Y1396156D01*
X337772Y1395795D01*
X337542Y1395278D01*
X337465Y1394813D01*
X339075D01*
G01X319890Y1454488D02*
Y1457588D01*
X320810D01*
X321117Y1457433D01*
X321347Y1457071D01*
X321424Y1456658D01*
X321347Y1456245D01*
X321155Y1455935D01*
X320810Y1455780D01*
X319890D01*
G01X323757Y1454488D02*
Y1457588D01*
X323297Y1456968D01*
G01Y1454488D02*
X324217D01*
G01X326129Y1455780D02*
X326397Y1456141D01*
X326627Y1456348D01*
X326934Y1456451D01*
X327202Y1456348D01*
X327394Y1456141D01*
X327547Y1455831D01*
X327585Y1455470D01*
X327547Y1455160D01*
X327394Y1454850D01*
X327164Y1454591D01*
X326895Y1454488D01*
X326589Y1454591D01*
X326320Y1454901D01*
X326167Y1455366D01*
X326129Y1455883D01*
X326205Y1456555D01*
X326320Y1456916D01*
X326512Y1457278D01*
X326780Y1457536D01*
X327049Y1457588D01*
X327317Y1457485D01*
X327509Y1457226D01*
G01X334686Y1456168D02*
X334993Y1455910D01*
X335338Y1455755D01*
X335644D01*
X335951Y1455910D01*
X336181Y1456168D01*
X336296Y1456530D01*
X336219Y1456892D01*
X336028Y1457202D01*
X335683Y1457408D01*
X335223Y1457512D01*
X334954Y1457718D01*
X334839Y1458080D01*
X334916Y1458442D01*
X335108Y1458700D01*
X335376Y1458855D01*
X335644D01*
X335913Y1458752D01*
X336143Y1458493D01*
G01X338591Y1455755D02*
Y1458855D01*
X338131Y1458235D01*
G01Y1455755D02*
X339051D01*
G01X320902Y1560148D02*
Y1563248D01*
X321822D01*
X322129Y1563093D01*
X322359Y1562731D01*
X322436Y1562318D01*
X322359Y1561905D01*
X322167Y1561595D01*
X321822Y1561440D01*
X320902D01*
G01X324769Y1560148D02*
Y1563248D01*
X324309Y1562628D01*
G01Y1560148D02*
X325229D01*
G01X327792D02*
X327869Y1560820D01*
X327984Y1561388D01*
X328137Y1561905D01*
X328329Y1562473D01*
X328636Y1563248D01*
X327102D01*
G01X333984Y1561485D02*
X334291Y1561227D01*
X334636Y1561072D01*
X334942D01*
X335249Y1561227D01*
X335479Y1561485D01*
X335594Y1561847D01*
X335517Y1562209D01*
X335326Y1562519D01*
X334981Y1562725D01*
X334521Y1562829D01*
X334252Y1563035D01*
X334137Y1563397D01*
X334214Y1563759D01*
X334406Y1564017D01*
X334674Y1564172D01*
X334942D01*
X335211Y1564069D01*
X335441Y1563810D01*
G01X337889Y1561072D02*
Y1564172D01*
X337429Y1563552D01*
G01Y1561072D02*
X338349D01*
G01X340261Y1563655D02*
X340491Y1563965D01*
X340759Y1564120D01*
X341066Y1564172D01*
X341449Y1564069D01*
X341717Y1563810D01*
X341794Y1563500D01*
X341756Y1563190D01*
X341602Y1562932D01*
X340836Y1562415D01*
X340491Y1562054D01*
X340261Y1561537D01*
X340184Y1561072D01*
X341794D01*
G01X318041Y1629604D02*
Y1632704D01*
X318961D01*
X319268Y1632549D01*
X319498Y1632187D01*
X319575Y1631774D01*
X319498Y1631361D01*
X319306Y1631051D01*
X318961Y1630896D01*
X318041D01*
G01X321908Y1629604D02*
Y1632704D01*
X321448Y1632084D01*
G01Y1629604D02*
X322368D01*
G01X324280Y1630896D02*
X324548Y1631257D01*
X324778Y1631464D01*
X325085Y1631567D01*
X325353Y1631464D01*
X325545Y1631257D01*
X325698Y1630947D01*
X325736Y1630586D01*
X325698Y1630276D01*
X325545Y1629966D01*
X325315Y1629707D01*
X325046Y1629604D01*
X324740Y1629707D01*
X324471Y1630017D01*
X324318Y1630482D01*
X324280Y1630999D01*
X324356Y1631671D01*
X324471Y1632032D01*
X324663Y1632394D01*
X324931Y1632652D01*
X325200Y1632704D01*
X325468Y1632601D01*
X325660Y1632342D01*
G01X333331Y1631204D02*
X333638Y1630946D01*
X333983Y1630791D01*
X334289D01*
X334596Y1630946D01*
X334826Y1631204D01*
X334941Y1631566D01*
X334864Y1631928D01*
X334673Y1632238D01*
X334328Y1632444D01*
X333868Y1632548D01*
X333599Y1632754D01*
X333484Y1633116D01*
X333561Y1633478D01*
X333753Y1633736D01*
X334021Y1633891D01*
X334289D01*
X334558Y1633788D01*
X334788Y1633529D01*
G01X337236Y1630791D02*
Y1633891D01*
X336776Y1633271D01*
G01Y1630791D02*
X337696D01*
G01X316858Y1744019D02*
Y1747119D01*
X317778D01*
X318085Y1746964D01*
X318315Y1746602D01*
X318392Y1746189D01*
X318315Y1745776D01*
X318123Y1745466D01*
X317778Y1745311D01*
X316858D01*
G01X320725Y1744019D02*
Y1747119D01*
X320265Y1746499D01*
G01Y1744019D02*
X321185D01*
G01X323748D02*
X323825Y1744691D01*
X323940Y1745259D01*
X324093Y1745776D01*
X324285Y1746344D01*
X324592Y1747119D01*
X323058D01*
G01X329536Y1744685D02*
X329843Y1744427D01*
X330188Y1744272D01*
X330494D01*
X330801Y1744427D01*
X331031Y1744685D01*
X331146Y1745047D01*
X331069Y1745409D01*
X330878Y1745719D01*
X330533Y1745925D01*
X330073Y1746029D01*
X329804Y1746235D01*
X329689Y1746597D01*
X329766Y1746959D01*
X329958Y1747217D01*
X330226Y1747372D01*
X330494D01*
X330763Y1747269D01*
X330993Y1747010D01*
G01X333441Y1744272D02*
Y1747372D01*
X332981Y1746752D01*
G01Y1744272D02*
X333901D01*
G01X335813Y1746855D02*
X336043Y1747165D01*
X336311Y1747320D01*
X336618Y1747372D01*
X337001Y1747269D01*
X337269Y1747010D01*
X337346Y1746700D01*
X337308Y1746390D01*
X337154Y1746132D01*
X336388Y1745615D01*
X336043Y1745254D01*
X335813Y1744737D01*
X335736Y1744272D01*
X337346D01*
G01X324400Y1804895D02*
Y1807995D01*
X325320D01*
X325627Y1807840D01*
X325857Y1807478D01*
X325934Y1807065D01*
X325857Y1806652D01*
X325665Y1806342D01*
X325320Y1806187D01*
X324400D01*
G01X328267Y1804895D02*
Y1807995D01*
X327807Y1807375D01*
G01Y1804895D02*
X328727D01*
G01X330639Y1806187D02*
X330907Y1806548D01*
X331137Y1806755D01*
X331444Y1806858D01*
X331712Y1806755D01*
X331904Y1806548D01*
X332057Y1806238D01*
X332095Y1805877D01*
X332057Y1805567D01*
X331904Y1805257D01*
X331674Y1804998D01*
X331405Y1804895D01*
X331099Y1804998D01*
X330830Y1805308D01*
X330677Y1805773D01*
X330639Y1806290D01*
X330715Y1806962D01*
X330830Y1807323D01*
X331022Y1807685D01*
X331290Y1807943D01*
X331559Y1807995D01*
X331827Y1807892D01*
X332019Y1807633D01*
G01X319800Y1918028D02*
Y1921128D01*
X320720D01*
X321027Y1920973D01*
X321257Y1920611D01*
X321334Y1920198D01*
X321257Y1919785D01*
X321065Y1919475D01*
X320720Y1919320D01*
X319800D01*
G01X323667Y1918028D02*
Y1921128D01*
X323207Y1920508D01*
G01Y1918028D02*
X324127D01*
G01X326690D02*
X326767Y1918700D01*
X326882Y1919268D01*
X327035Y1919785D01*
X327227Y1920353D01*
X327534Y1921128D01*
X326000D01*
G01X335050Y1918304D02*
X335357Y1918046D01*
X335702Y1917891D01*
X336008D01*
X336315Y1918046D01*
X336545Y1918304D01*
X336660Y1918666D01*
X336583Y1919028D01*
X336392Y1919338D01*
X336047Y1919544D01*
X335587Y1919648D01*
X335318Y1919854D01*
X335203Y1920216D01*
X335280Y1920578D01*
X335472Y1920836D01*
X335740Y1920991D01*
X336008D01*
X336277Y1920888D01*
X336507Y1920629D01*
G01X338955Y1917891D02*
Y1920991D01*
X338495Y1920371D01*
G01Y1917891D02*
X339415D01*
G01X341327Y1920474D02*
X341557Y1920784D01*
X341825Y1920939D01*
X342132Y1920991D01*
X342515Y1920888D01*
X342783Y1920629D01*
X342860Y1920319D01*
X342822Y1920009D01*
X342668Y1919751D01*
X341902Y1919234D01*
X341557Y1918873D01*
X341327Y1918356D01*
X341250Y1917891D01*
X342860D01*
G01X318545Y1985456D02*
X321545D01*
G01X321645Y1988556D02*
Y1982356D01*
X318445D01*
Y1988556D01*
X321645D01*
G01X323303Y1985456D02*
X326303D01*
G01X326403Y1988556D02*
Y1982356D01*
X323203D01*
Y1988556D01*
X326403D01*
G01X331095Y1981045D02*
Y1984145D01*
X332015D01*
X332322Y1983990D01*
X332552Y1983628D01*
X332629Y1983215D01*
X332552Y1982802D01*
X332360Y1982492D01*
X332015Y1982337D01*
X331095D01*
G01X334962Y1981045D02*
Y1984145D01*
X334502Y1983525D01*
G01Y1981045D02*
X335422D01*
G01X337334Y1982337D02*
X337602Y1982698D01*
X337832Y1982905D01*
X338139Y1983008D01*
X338407Y1982905D01*
X338599Y1982698D01*
X338752Y1982388D01*
X338790Y1982027D01*
X338752Y1981717D01*
X338599Y1981407D01*
X338369Y1981148D01*
X338100Y1981045D01*
X337794Y1981148D01*
X337525Y1981458D01*
X337372Y1981923D01*
X337334Y1982440D01*
X337410Y1983112D01*
X337525Y1983473D01*
X337717Y1983835D01*
X337985Y1984093D01*
X338254Y1984145D01*
X338522Y1984042D01*
X338714Y1983783D01*
G01X318349Y1998233D02*
X318194Y1998003D01*
X318091Y1997735D01*
Y1997428D01*
X318246Y1997083D01*
X318504Y1996815D01*
X318814Y1996623D01*
X319331Y1996470D01*
X319796Y1996432D01*
X320261Y1996508D01*
X320571Y1996623D01*
X320881Y1996853D01*
X321088Y1997122D01*
X321191Y1997390D01*
Y1997658D01*
X321088Y1997927D01*
X320933Y1998157D01*
X320726Y1998348D01*
G01X321191Y2000413D02*
X320519Y2000490D01*
X319951Y2000605D01*
X319434Y2000758D01*
X318866Y2000950D01*
X318091Y2001257D01*
Y1999723D01*
G01X320829Y2002938D02*
X321088Y2003207D01*
X321191Y2003513D01*
X321088Y2003820D01*
X320778Y2004088D01*
X320313Y2004280D01*
X319848Y2004357D01*
X319279D01*
X318814Y2004280D01*
X318401Y2004088D01*
X318194Y2003858D01*
X318091Y2003590D01*
X318194Y2003283D01*
X318401Y2003053D01*
X318711Y2002900D01*
X319124Y2002823D01*
X319486Y2002900D01*
X319848Y2003092D01*
X320054Y2003322D01*
X320106Y2003590D01*
X320003Y2003897D01*
X319744Y2004127D01*
X319279Y2004357D01*
G01X322975Y1998233D02*
X322820Y1998003D01*
X322717Y1997735D01*
Y1997428D01*
X322872Y1997083D01*
X323130Y1996815D01*
X323440Y1996623D01*
X323957Y1996470D01*
X324422Y1996432D01*
X324887Y1996508D01*
X325197Y1996623D01*
X325507Y1996853D01*
X325714Y1997122D01*
X325817Y1997390D01*
Y1997658D01*
X325714Y1997927D01*
X325559Y1998157D01*
X325352Y1998348D01*
G01X325817Y2000490D02*
X325765Y2000758D01*
X325610Y2001065D01*
X325352Y2001257D01*
X324990Y2001333D01*
X324629Y2001257D01*
X324319Y2001027D01*
X324164Y2000682D01*
Y2000298D01*
X324060Y2000068D01*
X323802Y1999877D01*
X323440Y1999800D01*
X323079Y1999915D01*
X322820Y2000183D01*
X322717Y2000490D01*
X322820Y2000797D01*
X323079Y2001065D01*
X323440Y2001180D01*
X323802Y2001103D01*
X324060Y2000912D01*
X324164Y2000682D01*
Y2000298D01*
X324319Y1999953D01*
X324629Y1999723D01*
X324990Y1999647D01*
X325352Y1999723D01*
X325610Y1999915D01*
X325765Y2000222D01*
X325817Y2000490D01*
G01X322717Y2003590D02*
X322820Y2003283D01*
X323079Y2003053D01*
X323389Y2002900D01*
X323802Y2002785D01*
X324267Y2002747D01*
X324732Y2002785D01*
X325145Y2002900D01*
X325455Y2003053D01*
X325714Y2003283D01*
X325817Y2003590D01*
X325714Y2003897D01*
X325455Y2004127D01*
X325145Y2004280D01*
X324732Y2004395D01*
X324267Y2004433D01*
X323802Y2004395D01*
X323389Y2004280D01*
X323079Y2004127D01*
X322820Y2003897D01*
X322717Y2003590D01*
G01X350500Y-72000D02*
Y-80000D01*
G01X348200Y-72000D02*
X352800D01*
G01X356600Y-76667D02*
X357300Y-75733D01*
X357900Y-75200D01*
X358700Y-74933D01*
X359400Y-75200D01*
X359900Y-75733D01*
X360300Y-76533D01*
X360400Y-77467D01*
X360300Y-78267D01*
X359900Y-79067D01*
X359300Y-79733D01*
X358600Y-80000D01*
X357800Y-79733D01*
X357100Y-78934D01*
X356700Y-77733D01*
X356600Y-76400D01*
X356800Y-74667D01*
X357100Y-73733D01*
X357600Y-72800D01*
X358300Y-72133D01*
X359000Y-72000D01*
X359700Y-72267D01*
X360200Y-72933D01*
G01X363900Y-80000D02*
Y-72000D01*
X366500Y-78667D01*
X369100Y-72000D01*
Y-80000D01*
G01X371500Y-82667D02*
X377500D01*
G01X380500Y-80000D02*
Y-72000D01*
X382900D01*
X383700Y-72400D01*
X384300Y-73333D01*
X384500Y-74400D01*
X384300Y-75467D01*
X383800Y-76267D01*
X382900Y-76667D01*
X380500D01*
G01X388300Y-80000D02*
Y-72000D01*
X390300D01*
X391100Y-72400D01*
X391700Y-72933D01*
X392200Y-73733D01*
X392600Y-74667D01*
X392700Y-76000D01*
X392600Y-77333D01*
X392200Y-78267D01*
X391700Y-79067D01*
X391100Y-79600D01*
X390300Y-80000D01*
X388300D01*
G01X399300Y-75733D02*
X399700Y-75333D01*
X400000Y-74667D01*
X400200Y-73733D01*
X400000Y-72933D01*
X399600Y-72400D01*
X398900Y-72000D01*
X396200D01*
Y-80000D01*
X399500D01*
X400200Y-79467D01*
X400600Y-78667D01*
X400800Y-77733D01*
X400600Y-76800D01*
X400000Y-76000D01*
X399300Y-75733D01*
X396200D01*
G01X403500Y-82667D02*
X409500D01*
G01X412300Y-80000D02*
Y-72000D01*
X414300D01*
X415100Y-72400D01*
X415700Y-72933D01*
X416200Y-73733D01*
X416600Y-74667D01*
X416700Y-76000D01*
X416600Y-77333D01*
X416200Y-78267D01*
X415700Y-79067D01*
X415100Y-79600D01*
X414300Y-80000D01*
X412300D01*
G01X419500Y-82667D02*
X425500D01*
G01X431300Y-75733D02*
X431700Y-75333D01*
X432000Y-74667D01*
X432200Y-73733D01*
X432000Y-72933D01*
X431600Y-72400D01*
X430900Y-72000D01*
X428200D01*
Y-80000D01*
X431500D01*
X432200Y-79467D01*
X432600Y-78667D01*
X432800Y-77733D01*
X432600Y-76800D01*
X432000Y-76000D01*
X431300Y-75733D01*
X428200D01*
G01X436300Y-80000D02*
Y-72000D01*
X438300D01*
X439100Y-72400D01*
X439700Y-72933D01*
X440200Y-73733D01*
X440600Y-74667D01*
X440700Y-76000D01*
X440600Y-77333D01*
X440200Y-78267D01*
X439700Y-79067D01*
X439100Y-79600D01*
X438300Y-80000D01*
X436300D01*
G01X359570Y12643D02*
X359877Y12385D01*
X360222Y12230D01*
X360528D01*
X360835Y12385D01*
X361065Y12643D01*
X361180Y13005D01*
X361103Y13367D01*
X360912Y13677D01*
X360567Y13883D01*
X360107Y13987D01*
X359838Y14193D01*
X359723Y14555D01*
X359800Y14917D01*
X359992Y15175D01*
X360260Y15330D01*
X360528D01*
X360797Y15227D01*
X361027Y14968D01*
G01X363398Y12230D02*
X363475Y12902D01*
X363590Y13470D01*
X363743Y13987D01*
X363935Y14555D01*
X364242Y15330D01*
X362708D01*
G01X359568Y38053D02*
X359875Y37795D01*
X360220Y37640D01*
X360526D01*
X360833Y37795D01*
X361063Y38053D01*
X361178Y38415D01*
X361101Y38777D01*
X360910Y39087D01*
X360565Y39293D01*
X360105Y39397D01*
X359836Y39603D01*
X359721Y39965D01*
X359798Y40327D01*
X359990Y40585D01*
X360258Y40740D01*
X360526D01*
X360795Y40637D01*
X361025Y40378D01*
G01X362745Y38932D02*
X363013Y39293D01*
X363243Y39500D01*
X363550Y39603D01*
X363818Y39500D01*
X364010Y39293D01*
X364163Y38983D01*
X364201Y38622D01*
X364163Y38312D01*
X364010Y38002D01*
X363780Y37743D01*
X363511Y37640D01*
X363205Y37743D01*
X362936Y38053D01*
X362783Y38518D01*
X362745Y39035D01*
X362821Y39707D01*
X362936Y40068D01*
X363128Y40430D01*
X363396Y40688D01*
X363665Y40740D01*
X363933Y40637D01*
X364125Y40378D01*
G01X378842Y78780D02*
G03I-19000J0D01*
G01X339987Y97980D02*
Y101080D01*
G01X341597D02*
Y97980D01*
G01Y99530D02*
X339987D01*
G01X343164Y100563D02*
X343394Y100873D01*
X343662Y101028D01*
X343969Y101080D01*
X344352Y100977D01*
X344620Y100718D01*
X344697Y100408D01*
X344659Y100098D01*
X344505Y99840D01*
X343739Y99323D01*
X343394Y98962D01*
X343164Y98445D01*
X343087Y97980D01*
X344697D01*
G01X346149Y98445D02*
X346379Y98187D01*
X346647Y98032D01*
X346992Y97980D01*
X347337Y98083D01*
X347605Y98290D01*
X347797Y98652D01*
X347835Y99065D01*
X347759Y99478D01*
X347567Y99737D01*
X347299Y99943D01*
X347030Y99995D01*
X346762Y99943D01*
X346417Y99737D01*
X346532Y101080D01*
X347567D01*
G01X361698Y170078D02*
X362005Y169820D01*
X362350Y169665D01*
X362656D01*
X362963Y169820D01*
X363193Y170078D01*
X363308Y170440D01*
X363231Y170802D01*
X363040Y171112D01*
X362695Y171318D01*
X362235Y171422D01*
X361966Y171628D01*
X361851Y171990D01*
X361928Y172352D01*
X362120Y172610D01*
X362388Y172765D01*
X362656D01*
X362925Y172662D01*
X363155Y172403D01*
G01X365526Y169665D02*
X365603Y170337D01*
X365718Y170905D01*
X365871Y171422D01*
X366063Y171990D01*
X366370Y172765D01*
X364836D01*
G01X359295Y229963D02*
X359602Y229705D01*
X359947Y229550D01*
X360253D01*
X360560Y229705D01*
X360790Y229963D01*
X360905Y230325D01*
X360828Y230687D01*
X360637Y230997D01*
X360292Y231203D01*
X359832Y231307D01*
X359563Y231513D01*
X359448Y231875D01*
X359525Y232237D01*
X359717Y232495D01*
X359985Y232650D01*
X360253D01*
X360522Y232547D01*
X360752Y232288D01*
G01X362472Y230842D02*
X362740Y231203D01*
X362970Y231410D01*
X363277Y231513D01*
X363545Y231410D01*
X363737Y231203D01*
X363890Y230893D01*
X363928Y230532D01*
X363890Y230222D01*
X363737Y229912D01*
X363507Y229653D01*
X363238Y229550D01*
X362932Y229653D01*
X362663Y229963D01*
X362510Y230428D01*
X362472Y230945D01*
X362548Y231617D01*
X362663Y231978D01*
X362855Y232340D01*
X363123Y232598D01*
X363392Y232650D01*
X363660Y232547D01*
X363852Y232288D01*
G01X378842Y253780D02*
G03I-19000J0D01*
G01X339987Y272980D02*
Y276080D01*
G01X341597D02*
Y272980D01*
G01Y274530D02*
X339987D01*
G01X343892Y272980D02*
Y276080D01*
X343432Y275460D01*
G01Y272980D02*
X344352D01*
G01X346264Y274272D02*
X346532Y274633D01*
X346762Y274840D01*
X347069Y274943D01*
X347337Y274840D01*
X347529Y274633D01*
X347682Y274323D01*
X347720Y273962D01*
X347682Y273652D01*
X347529Y273342D01*
X347299Y273083D01*
X347030Y272980D01*
X346724Y273083D01*
X346455Y273393D01*
X346302Y273858D01*
X346264Y274375D01*
X346340Y275047D01*
X346455Y275408D01*
X346647Y275770D01*
X346915Y276028D01*
X347184Y276080D01*
X347452Y275977D01*
X347644Y275718D01*
G01X362425Y344946D02*
X362732Y344688D01*
X363077Y344533D01*
X363383D01*
X363690Y344688D01*
X363920Y344946D01*
X364035Y345308D01*
X363958Y345670D01*
X363767Y345980D01*
X363422Y346186D01*
X362962Y346290D01*
X362693Y346496D01*
X362578Y346858D01*
X362655Y347220D01*
X362847Y347478D01*
X363115Y347633D01*
X363383D01*
X363652Y347530D01*
X363882Y347271D01*
G01X366253Y344533D02*
X366330Y345205D01*
X366445Y345773D01*
X366598Y346290D01*
X366790Y346858D01*
X367097Y347633D01*
X365563D01*
G01X359973Y405493D02*
X360280Y405235D01*
X360625Y405080D01*
X360931D01*
X361238Y405235D01*
X361468Y405493D01*
X361583Y405855D01*
X361506Y406217D01*
X361315Y406527D01*
X360970Y406733D01*
X360510Y406837D01*
X360241Y407043D01*
X360126Y407405D01*
X360203Y407767D01*
X360395Y408025D01*
X360663Y408180D01*
X360931D01*
X361200Y408077D01*
X361430Y407818D01*
G01X363150Y406372D02*
X363418Y406733D01*
X363648Y406940D01*
X363955Y407043D01*
X364223Y406940D01*
X364415Y406733D01*
X364568Y406423D01*
X364606Y406062D01*
X364568Y405752D01*
X364415Y405442D01*
X364185Y405183D01*
X363916Y405080D01*
X363610Y405183D01*
X363341Y405493D01*
X363188Y405958D01*
X363150Y406475D01*
X363226Y407147D01*
X363341Y407508D01*
X363533Y407870D01*
X363801Y408128D01*
X364070Y408180D01*
X364338Y408077D01*
X364530Y407818D01*
G01X378842Y428779D02*
G03I-19000J0D01*
G01X339987Y447979D02*
Y451079D01*
G01X341597D02*
Y447979D01*
G01Y449529D02*
X339987D01*
G01X343892Y447979D02*
Y451079D01*
X343432Y450459D01*
G01Y447979D02*
X344352D01*
G01X346915D02*
X346992Y448651D01*
X347107Y449219D01*
X347260Y449736D01*
X347452Y450304D01*
X347759Y451079D01*
X346225D01*
G01X360116Y519148D02*
X360423Y518890D01*
X360768Y518735D01*
X361074D01*
X361381Y518890D01*
X361611Y519148D01*
X361726Y519510D01*
X361649Y519872D01*
X361458Y520182D01*
X361113Y520388D01*
X360653Y520492D01*
X360384Y520698D01*
X360269Y521060D01*
X360346Y521422D01*
X360538Y521680D01*
X360806Y521835D01*
X361074D01*
X361343Y521732D01*
X361573Y521473D01*
G01X363944Y518735D02*
X364021Y519407D01*
X364136Y519975D01*
X364289Y520492D01*
X364481Y521060D01*
X364788Y521835D01*
X363254D01*
G01X358789Y580593D02*
X359096Y580335D01*
X359441Y580180D01*
X359747D01*
X360054Y580335D01*
X360284Y580593D01*
X360399Y580955D01*
X360322Y581317D01*
X360131Y581627D01*
X359786Y581833D01*
X359326Y581937D01*
X359057Y582143D01*
X358942Y582505D01*
X359019Y582867D01*
X359211Y583125D01*
X359479Y583280D01*
X359747D01*
X360016Y583177D01*
X360246Y582918D01*
G01X361966Y581472D02*
X362234Y581833D01*
X362464Y582040D01*
X362771Y582143D01*
X363039Y582040D01*
X363231Y581833D01*
X363384Y581523D01*
X363422Y581162D01*
X363384Y580852D01*
X363231Y580542D01*
X363001Y580283D01*
X362732Y580180D01*
X362426Y580283D01*
X362157Y580593D01*
X362004Y581058D01*
X361966Y581575D01*
X362042Y582247D01*
X362157Y582608D01*
X362349Y582970D01*
X362617Y583228D01*
X362886Y583280D01*
X363154Y583177D01*
X363346Y582918D01*
G01X378842Y603779D02*
G03I-19000J0D01*
G01X339987Y622979D02*
Y626079D01*
G01X341597D02*
Y622979D01*
G01Y624529D02*
X339987D01*
G01X343164Y625562D02*
X343394Y625872D01*
X343662Y626027D01*
X343969Y626079D01*
X344352Y625976D01*
X344620Y625717D01*
X344697Y625407D01*
X344659Y625097D01*
X344505Y624839D01*
X343739Y624322D01*
X343394Y623961D01*
X343164Y623444D01*
X343087Y622979D01*
X344697D01*
G01X346264Y625562D02*
X346494Y625872D01*
X346762Y626027D01*
X347069Y626079D01*
X347452Y625976D01*
X347720Y625717D01*
X347797Y625407D01*
X347759Y625097D01*
X347605Y624839D01*
X346839Y624322D01*
X346494Y623961D01*
X346264Y623444D01*
X346187Y622979D01*
X347797D01*
G01X358131Y755211D02*
X358438Y754953D01*
X358783Y754798D01*
X359089D01*
X359396Y754953D01*
X359626Y755211D01*
X359741Y755573D01*
X359664Y755935D01*
X359473Y756245D01*
X359128Y756451D01*
X358668Y756555D01*
X358399Y756761D01*
X358284Y757123D01*
X358361Y757485D01*
X358553Y757743D01*
X358821Y757898D01*
X359089D01*
X359358Y757795D01*
X359588Y757536D01*
G01X361308Y756090D02*
X361576Y756451D01*
X361806Y756658D01*
X362113Y756761D01*
X362381Y756658D01*
X362573Y756451D01*
X362726Y756141D01*
X362764Y755780D01*
X362726Y755470D01*
X362573Y755160D01*
X362343Y754901D01*
X362074Y754798D01*
X361768Y754901D01*
X361499Y755211D01*
X361346Y755676D01*
X361308Y756193D01*
X361384Y756865D01*
X361499Y757226D01*
X361691Y757588D01*
X361959Y757846D01*
X362228Y757898D01*
X362496Y757795D01*
X362688Y757536D01*
G01X378842Y778780D02*
G03I-19000J0D01*
G01X339987Y797980D02*
Y801080D01*
G01X341597D02*
Y797980D01*
G01Y799530D02*
X339987D01*
G01X343164Y800563D02*
X343394Y800873D01*
X343662Y801028D01*
X343969Y801080D01*
X344352Y800977D01*
X344620Y800718D01*
X344697Y800408D01*
X344659Y800098D01*
X344505Y799840D01*
X343739Y799323D01*
X343394Y798962D01*
X343164Y798445D01*
X343087Y797980D01*
X344697D01*
G01X346992Y801080D02*
X346685Y800977D01*
X346455Y800718D01*
X346302Y800408D01*
X346187Y799995D01*
X346149Y799530D01*
X346187Y799065D01*
X346302Y798652D01*
X346455Y798342D01*
X346685Y798083D01*
X346992Y797980D01*
X347299Y798083D01*
X347529Y798342D01*
X347682Y798652D01*
X347797Y799065D01*
X347835Y799530D01*
X347797Y799995D01*
X347682Y800408D01*
X347529Y800718D01*
X347299Y800977D01*
X346992Y801080D01*
G01X359311Y869995D02*
X359618Y869737D01*
X359963Y869582D01*
X360269D01*
X360576Y869737D01*
X360806Y869995D01*
X360921Y870357D01*
X360844Y870719D01*
X360653Y871029D01*
X360308Y871235D01*
X359848Y871339D01*
X359579Y871545D01*
X359464Y871907D01*
X359541Y872269D01*
X359733Y872527D01*
X360001Y872682D01*
X360269D01*
X360538Y872579D01*
X360768Y872320D01*
G01X363139Y869582D02*
X363216Y870254D01*
X363331Y870822D01*
X363484Y871339D01*
X363676Y871907D01*
X363983Y872682D01*
X362449D01*
G01X361026Y930332D02*
X361333Y930074D01*
X361678Y929919D01*
X361984D01*
X362291Y930074D01*
X362521Y930332D01*
X362636Y930694D01*
X362559Y931056D01*
X362368Y931366D01*
X362023Y931572D01*
X361563Y931676D01*
X361294Y931882D01*
X361179Y932244D01*
X361256Y932606D01*
X361448Y932864D01*
X361716Y933019D01*
X361984D01*
X362253Y932916D01*
X362483Y932657D01*
G01X364203Y931211D02*
X364471Y931572D01*
X364701Y931779D01*
X365008Y931882D01*
X365276Y931779D01*
X365468Y931572D01*
X365621Y931262D01*
X365659Y930901D01*
X365621Y930591D01*
X365468Y930281D01*
X365238Y930022D01*
X364969Y929919D01*
X364663Y930022D01*
X364394Y930332D01*
X364241Y930797D01*
X364203Y931314D01*
X364279Y931986D01*
X364394Y932347D01*
X364586Y932709D01*
X364854Y932967D01*
X365123Y933019D01*
X365391Y932916D01*
X365583Y932657D01*
G01X378842Y953780D02*
G03I-19000J0D01*
G01X339987Y972980D02*
Y976080D01*
G01X341597D02*
Y972980D01*
G01Y974530D02*
X339987D01*
G01X343892Y972980D02*
Y976080D01*
X343432Y975460D01*
G01Y972980D02*
X344352D01*
G01X346992D02*
X347260Y973032D01*
X347567Y973187D01*
X347759Y973445D01*
X347835Y973807D01*
X347759Y974168D01*
X347529Y974478D01*
X347184Y974633D01*
X346800D01*
X346570Y974737D01*
X346379Y974995D01*
X346302Y975357D01*
X346417Y975718D01*
X346685Y975977D01*
X346992Y976080D01*
X347299Y975977D01*
X347567Y975718D01*
X347682Y975357D01*
X347605Y974995D01*
X347414Y974737D01*
X347184Y974633D01*
X346800D01*
X346455Y974478D01*
X346225Y974168D01*
X346149Y973807D01*
X346225Y973445D01*
X346417Y973187D01*
X346724Y973032D01*
X346992Y972980D01*
G01X358600Y1046029D02*
X358907Y1045771D01*
X359252Y1045616D01*
X359558D01*
X359865Y1045771D01*
X360095Y1046029D01*
X360210Y1046391D01*
X360133Y1046753D01*
X359942Y1047063D01*
X359597Y1047269D01*
X359137Y1047373D01*
X358868Y1047579D01*
X358753Y1047941D01*
X358830Y1048303D01*
X359022Y1048561D01*
X359290Y1048716D01*
X359558D01*
X359827Y1048613D01*
X360057Y1048354D01*
G01X362428Y1045616D02*
X362505Y1046288D01*
X362620Y1046856D01*
X362773Y1047373D01*
X362965Y1047941D01*
X363272Y1048716D01*
X361738D01*
G01X359689Y1105185D02*
X359996Y1104927D01*
X360341Y1104772D01*
X360647D01*
X360954Y1104927D01*
X361184Y1105185D01*
X361299Y1105547D01*
X361222Y1105909D01*
X361031Y1106219D01*
X360686Y1106425D01*
X360226Y1106529D01*
X359957Y1106735D01*
X359842Y1107097D01*
X359919Y1107459D01*
X360111Y1107717D01*
X360379Y1107872D01*
X360647D01*
X360916Y1107769D01*
X361146Y1107510D01*
G01X362866Y1106064D02*
X363134Y1106425D01*
X363364Y1106632D01*
X363671Y1106735D01*
X363939Y1106632D01*
X364131Y1106425D01*
X364284Y1106115D01*
X364322Y1105754D01*
X364284Y1105444D01*
X364131Y1105134D01*
X363901Y1104875D01*
X363632Y1104772D01*
X363326Y1104875D01*
X363057Y1105185D01*
X362904Y1105650D01*
X362866Y1106167D01*
X362942Y1106839D01*
X363057Y1107200D01*
X363249Y1107562D01*
X363517Y1107820D01*
X363786Y1107872D01*
X364054Y1107769D01*
X364246Y1107510D01*
G01X378842Y1128779D02*
G03I-19000J0D01*
G01X339987Y1147979D02*
Y1151079D01*
G01X341597D02*
Y1147979D01*
G01Y1149529D02*
X339987D01*
G01X343164Y1150562D02*
X343394Y1150872D01*
X343662Y1151027D01*
X343969Y1151079D01*
X344352Y1150976D01*
X344620Y1150717D01*
X344697Y1150407D01*
X344659Y1150097D01*
X344505Y1149839D01*
X343739Y1149322D01*
X343394Y1148961D01*
X343164Y1148444D01*
X343087Y1147979D01*
X344697D01*
G01X346992D02*
Y1151079D01*
X346532Y1150459D01*
G01Y1147979D02*
X347452D01*
G01X359655Y1221271D02*
X359962Y1221013D01*
X360307Y1220858D01*
X360613D01*
X360920Y1221013D01*
X361150Y1221271D01*
X361265Y1221633D01*
X361188Y1221995D01*
X360997Y1222305D01*
X360652Y1222511D01*
X360192Y1222615D01*
X359923Y1222821D01*
X359808Y1223183D01*
X359885Y1223545D01*
X360077Y1223803D01*
X360345Y1223958D01*
X360613D01*
X360882Y1223855D01*
X361112Y1223596D01*
G01X363483Y1220858D02*
X363560Y1221530D01*
X363675Y1222098D01*
X363828Y1222615D01*
X364020Y1223183D01*
X364327Y1223958D01*
X362793D01*
G01X359439Y1280603D02*
X359746Y1280345D01*
X360091Y1280190D01*
X360397D01*
X360704Y1280345D01*
X360934Y1280603D01*
X361049Y1280965D01*
X360972Y1281327D01*
X360781Y1281637D01*
X360436Y1281843D01*
X359976Y1281947D01*
X359707Y1282153D01*
X359592Y1282515D01*
X359669Y1282877D01*
X359861Y1283135D01*
X360129Y1283290D01*
X360397D01*
X360666Y1283187D01*
X360896Y1282928D01*
G01X362616Y1281482D02*
X362884Y1281843D01*
X363114Y1282050D01*
X363421Y1282153D01*
X363689Y1282050D01*
X363881Y1281843D01*
X364034Y1281533D01*
X364072Y1281172D01*
X364034Y1280862D01*
X363881Y1280552D01*
X363651Y1280293D01*
X363382Y1280190D01*
X363076Y1280293D01*
X362807Y1280603D01*
X362654Y1281068D01*
X362616Y1281585D01*
X362692Y1282257D01*
X362807Y1282618D01*
X362999Y1282980D01*
X363267Y1283238D01*
X363536Y1283290D01*
X363804Y1283187D01*
X363996Y1282928D01*
G01X378842Y1303780D02*
G03I-19000J0D01*
G01X339987Y1322980D02*
Y1326080D01*
G01X341597D02*
Y1322980D01*
G01Y1324530D02*
X339987D01*
G01X343164Y1325563D02*
X343394Y1325873D01*
X343662Y1326028D01*
X343969Y1326080D01*
X344352Y1325977D01*
X344620Y1325718D01*
X344697Y1325408D01*
X344659Y1325098D01*
X344505Y1324840D01*
X343739Y1324323D01*
X343394Y1323962D01*
X343164Y1323445D01*
X343087Y1322980D01*
X344697D01*
G01X346264Y1324272D02*
X346532Y1324633D01*
X346762Y1324840D01*
X347069Y1324943D01*
X347337Y1324840D01*
X347529Y1324633D01*
X347682Y1324323D01*
X347720Y1323962D01*
X347682Y1323652D01*
X347529Y1323342D01*
X347299Y1323083D01*
X347030Y1322980D01*
X346724Y1323083D01*
X346455Y1323393D01*
X346302Y1323858D01*
X346264Y1324375D01*
X346340Y1325047D01*
X346455Y1325408D01*
X346647Y1325770D01*
X346915Y1326028D01*
X347184Y1326080D01*
X347452Y1325977D01*
X347644Y1325718D01*
G01X358296Y1394886D02*
X358603Y1394628D01*
X358948Y1394473D01*
X359254D01*
X359561Y1394628D01*
X359791Y1394886D01*
X359906Y1395248D01*
X359829Y1395610D01*
X359638Y1395920D01*
X359293Y1396126D01*
X358833Y1396230D01*
X358564Y1396436D01*
X358449Y1396798D01*
X358526Y1397160D01*
X358718Y1397418D01*
X358986Y1397573D01*
X359254D01*
X359523Y1397470D01*
X359753Y1397211D01*
G01X362124Y1394473D02*
X362201Y1395145D01*
X362316Y1395713D01*
X362469Y1396230D01*
X362661Y1396798D01*
X362968Y1397573D01*
X361434D01*
G01X359626Y1455377D02*
X359933Y1455119D01*
X360278Y1454964D01*
X360584D01*
X360891Y1455119D01*
X361121Y1455377D01*
X361236Y1455739D01*
X361159Y1456101D01*
X360968Y1456411D01*
X360623Y1456617D01*
X360163Y1456721D01*
X359894Y1456927D01*
X359779Y1457289D01*
X359856Y1457651D01*
X360048Y1457909D01*
X360316Y1458064D01*
X360584D01*
X360853Y1457961D01*
X361083Y1457702D01*
G01X362803Y1456256D02*
X363071Y1456617D01*
X363301Y1456824D01*
X363608Y1456927D01*
X363876Y1456824D01*
X364068Y1456617D01*
X364221Y1456307D01*
X364259Y1455946D01*
X364221Y1455636D01*
X364068Y1455326D01*
X363838Y1455067D01*
X363569Y1454964D01*
X363263Y1455067D01*
X362994Y1455377D01*
X362841Y1455842D01*
X362803Y1456359D01*
X362879Y1457031D01*
X362994Y1457392D01*
X363186Y1457754D01*
X363454Y1458012D01*
X363723Y1458064D01*
X363991Y1457961D01*
X364183Y1457702D01*
G01X378842Y1478780D02*
G03I-19000J0D01*
G01X339987Y1497980D02*
Y1501080D01*
G01X341597D02*
Y1497980D01*
G01Y1499530D02*
X339987D01*
G01X343164Y1500563D02*
X343394Y1500873D01*
X343662Y1501028D01*
X343969Y1501080D01*
X344352Y1500977D01*
X344620Y1500718D01*
X344697Y1500408D01*
X344659Y1500098D01*
X344505Y1499840D01*
X343739Y1499323D01*
X343394Y1498962D01*
X343164Y1498445D01*
X343087Y1497980D01*
X344697D01*
G01X346149Y1498600D02*
X346379Y1498238D01*
X346685Y1498032D01*
X347030Y1497980D01*
X347337Y1498032D01*
X347644Y1498290D01*
X347835Y1498600D01*
X347874Y1498910D01*
X347797Y1499272D01*
X347529Y1499530D01*
X347260Y1499633D01*
X346915D01*
G01X347260D02*
X347490Y1499788D01*
X347682Y1500047D01*
X347759Y1500357D01*
X347682Y1500667D01*
X347490Y1500925D01*
X347145Y1501080D01*
X346800Y1501028D01*
X346455Y1500822D01*
G01X361441Y1560664D02*
X361748Y1560406D01*
X362093Y1560251D01*
X362399D01*
X362706Y1560406D01*
X362936Y1560664D01*
X363051Y1561026D01*
X362974Y1561388D01*
X362783Y1561698D01*
X362438Y1561904D01*
X361978Y1562008D01*
X361709Y1562214D01*
X361594Y1562576D01*
X361671Y1562938D01*
X361863Y1563196D01*
X362131Y1563351D01*
X362399D01*
X362668Y1563248D01*
X362898Y1562989D01*
G01X365269Y1560251D02*
X365346Y1560923D01*
X365461Y1561491D01*
X365614Y1562008D01*
X365806Y1562576D01*
X366113Y1563351D01*
X364579D01*
G01X358139Y1630279D02*
X358446Y1630021D01*
X358791Y1629866D01*
X359097D01*
X359404Y1630021D01*
X359634Y1630279D01*
X359749Y1630641D01*
X359672Y1631003D01*
X359481Y1631313D01*
X359136Y1631519D01*
X358676Y1631623D01*
X358407Y1631829D01*
X358292Y1632191D01*
X358369Y1632553D01*
X358561Y1632811D01*
X358829Y1632966D01*
X359097D01*
X359366Y1632863D01*
X359596Y1632604D01*
G01X361316Y1631158D02*
X361584Y1631519D01*
X361814Y1631726D01*
X362121Y1631829D01*
X362389Y1631726D01*
X362581Y1631519D01*
X362734Y1631209D01*
X362772Y1630848D01*
X362734Y1630538D01*
X362581Y1630228D01*
X362351Y1629969D01*
X362082Y1629866D01*
X361776Y1629969D01*
X361507Y1630279D01*
X361354Y1630744D01*
X361316Y1631261D01*
X361392Y1631933D01*
X361507Y1632294D01*
X361699Y1632656D01*
X361967Y1632914D01*
X362236Y1632966D01*
X362504Y1632863D01*
X362696Y1632604D01*
G01X378842Y1653780D02*
G03I-19000J0D01*
G01X339987Y1672980D02*
Y1676080D01*
G01X341597D02*
Y1672980D01*
G01Y1674530D02*
X339987D01*
G01X343892Y1672980D02*
Y1676080D01*
X343432Y1675460D01*
G01Y1672980D02*
X344352D01*
G01X346149Y1673445D02*
X346379Y1673187D01*
X346647Y1673032D01*
X346992Y1672980D01*
X347337Y1673083D01*
X347605Y1673290D01*
X347797Y1673652D01*
X347835Y1674065D01*
X347759Y1674478D01*
X347567Y1674737D01*
X347299Y1674943D01*
X347030Y1674995D01*
X346762Y1674943D01*
X346417Y1674737D01*
X346532Y1676080D01*
X347567D01*
G01X358334Y1744266D02*
X358641Y1744008D01*
X358986Y1743853D01*
X359292D01*
X359599Y1744008D01*
X359829Y1744266D01*
X359944Y1744628D01*
X359867Y1744990D01*
X359676Y1745300D01*
X359331Y1745506D01*
X358871Y1745610D01*
X358602Y1745816D01*
X358487Y1746178D01*
X358564Y1746540D01*
X358756Y1746798D01*
X359024Y1746953D01*
X359292D01*
X359561Y1746850D01*
X359791Y1746591D01*
G01X362162Y1743853D02*
X362239Y1744525D01*
X362354Y1745093D01*
X362507Y1745610D01*
X362699Y1746178D01*
X363006Y1746953D01*
X361472D01*
G01X340093Y1807568D02*
X340400Y1807310D01*
X340745Y1807155D01*
X341051D01*
X341358Y1807310D01*
X341588Y1807568D01*
X341703Y1807930D01*
X341626Y1808292D01*
X341435Y1808602D01*
X341090Y1808808D01*
X340630Y1808912D01*
X340361Y1809118D01*
X340246Y1809480D01*
X340323Y1809842D01*
X340515Y1810100D01*
X340783Y1810255D01*
X341051D01*
X341320Y1810152D01*
X341550Y1809893D01*
G01X343998Y1807155D02*
Y1810255D01*
X343538Y1809635D01*
G01Y1807155D02*
X344458D01*
G01X361027Y1805547D02*
X361334Y1805289D01*
X361679Y1805134D01*
X361985D01*
X362292Y1805289D01*
X362522Y1805547D01*
X362637Y1805909D01*
X362560Y1806271D01*
X362369Y1806581D01*
X362024Y1806787D01*
X361564Y1806891D01*
X361295Y1807097D01*
X361180Y1807459D01*
X361257Y1807821D01*
X361449Y1808079D01*
X361717Y1808234D01*
X361985D01*
X362254Y1808131D01*
X362484Y1807872D01*
G01X364204Y1806426D02*
X364472Y1806787D01*
X364702Y1806994D01*
X365009Y1807097D01*
X365277Y1806994D01*
X365469Y1806787D01*
X365622Y1806477D01*
X365660Y1806116D01*
X365622Y1805806D01*
X365469Y1805496D01*
X365239Y1805237D01*
X364970Y1805134D01*
X364664Y1805237D01*
X364395Y1805547D01*
X364242Y1806012D01*
X364204Y1806529D01*
X364280Y1807201D01*
X364395Y1807562D01*
X364587Y1807924D01*
X364855Y1808182D01*
X365124Y1808234D01*
X365392Y1808131D01*
X365584Y1807872D01*
G01X378842Y1828779D02*
G03I-19000J0D01*
G01X339987Y1847979D02*
Y1851079D01*
G01X341597D02*
Y1847979D01*
G01Y1849529D02*
X339987D01*
G01X343892Y1847979D02*
Y1851079D01*
X343432Y1850459D01*
G01Y1847979D02*
X344352D01*
G01X346340Y1848341D02*
X346609Y1848082D01*
X346915Y1847979D01*
X347222Y1848082D01*
X347490Y1848392D01*
X347682Y1848857D01*
X347759Y1849322D01*
Y1849891D01*
X347682Y1850356D01*
X347490Y1850769D01*
X347260Y1850976D01*
X346992Y1851079D01*
X346685Y1850976D01*
X346455Y1850769D01*
X346302Y1850459D01*
X346225Y1850046D01*
X346302Y1849684D01*
X346494Y1849322D01*
X346724Y1849116D01*
X346992Y1849064D01*
X347299Y1849167D01*
X347529Y1849426D01*
X347759Y1849891D01*
G01X341028Y1981458D02*
X341335Y1981200D01*
X341680Y1981045D01*
X341986D01*
X342293Y1981200D01*
X342523Y1981458D01*
X342638Y1981820D01*
X342561Y1982182D01*
X342370Y1982492D01*
X342025Y1982698D01*
X341565Y1982802D01*
X341296Y1983008D01*
X341181Y1983370D01*
X341258Y1983732D01*
X341450Y1983990D01*
X341718Y1984145D01*
X341986D01*
X342255Y1984042D01*
X342485Y1983783D01*
G01X344933Y1981045D02*
Y1984145D01*
X344473Y1983525D01*
G01Y1981045D02*
X345393D01*
G01X378842Y2003780D02*
G03I-19000J0D01*
G01X339987Y2022980D02*
Y2026080D01*
G01X341597D02*
Y2022980D01*
G01Y2024530D02*
X339987D01*
G01X343164Y2025563D02*
X343394Y2025873D01*
X343662Y2026028D01*
X343969Y2026080D01*
X344352Y2025977D01*
X344620Y2025718D01*
X344697Y2025408D01*
X344659Y2025098D01*
X344505Y2024840D01*
X343739Y2024323D01*
X343394Y2023962D01*
X343164Y2023445D01*
X343087Y2022980D01*
X344697D01*
G01X347452D02*
Y2026080D01*
X346034Y2023858D01*
X347950D01*
G01X367867Y695209D02*
X368174Y694951D01*
X368519Y694796D01*
X368825D01*
X369132Y694951D01*
X369362Y695209D01*
X369477Y695571D01*
X369400Y695933D01*
X369209Y696243D01*
X368864Y696449D01*
X368404Y696553D01*
X368135Y696759D01*
X368020Y697121D01*
X368097Y697483D01*
X368289Y697741D01*
X368557Y697896D01*
X368825D01*
X369094Y697793D01*
X369324Y697534D01*
G01X371695Y694796D02*
X371772Y695468D01*
X371887Y696036D01*
X372040Y696553D01*
X372232Y697121D01*
X372539Y697896D01*
X371005D01*
G01X364173Y1917622D02*
X364480Y1917364D01*
X364825Y1917209D01*
X365131D01*
X365438Y1917364D01*
X365668Y1917622D01*
X365783Y1917984D01*
X365706Y1918346D01*
X365515Y1918656D01*
X365170Y1918862D01*
X364710Y1918966D01*
X364441Y1919172D01*
X364326Y1919534D01*
X364403Y1919896D01*
X364595Y1920154D01*
X364863Y1920309D01*
X365131D01*
X365400Y1920206D01*
X365630Y1919947D01*
G01X368001Y1917209D02*
X368078Y1917881D01*
X368193Y1918449D01*
X368346Y1918966D01*
X368538Y1919534D01*
X368845Y1920309D01*
X367311D01*
G01X371157Y1981062D02*
X371464Y1980804D01*
X371809Y1980649D01*
X372115D01*
X372422Y1980804D01*
X372652Y1981062D01*
X372767Y1981424D01*
X372690Y1981786D01*
X372499Y1982096D01*
X372154Y1982302D01*
X371694Y1982406D01*
X371425Y1982612D01*
X371310Y1982974D01*
X371387Y1983336D01*
X371579Y1983594D01*
X371847Y1983749D01*
X372115D01*
X372384Y1983646D01*
X372614Y1983387D01*
G01X374334Y1981941D02*
X374602Y1982302D01*
X374832Y1982509D01*
X375139Y1982612D01*
X375407Y1982509D01*
X375599Y1982302D01*
X375752Y1981992D01*
X375790Y1981631D01*
X375752Y1981321D01*
X375599Y1981011D01*
X375369Y1980752D01*
X375100Y1980649D01*
X374794Y1980752D01*
X374525Y1981062D01*
X374372Y1981527D01*
X374334Y1982044D01*
X374410Y1982716D01*
X374525Y1983077D01*
X374717Y1983439D01*
X374985Y1983697D01*
X375254Y1983749D01*
X375522Y1983646D01*
X375714Y1983387D01*
G01X418149Y1122D02*
Y53288D01*
G01Y176122D02*
Y228288D01*
G01Y351122D02*
Y403288D01*
G01X418150Y526122D02*
Y578288D01*
G01Y701122D02*
Y753288D01*
G01X418149Y876122D02*
Y928288D01*
G01Y1051122D02*
Y1103288D01*
G01Y1226122D02*
Y1278288D01*
G01Y1401122D02*
Y1453288D01*
G01Y1576122D02*
Y1628288D01*
G01Y1751122D02*
Y1803288D01*
G01Y1926122D02*
Y1978288D01*
G01X443300Y-130000D02*
Y-122000D01*
X445300D01*
X446100Y-122400D01*
X446700Y-122933D01*
X447200Y-123733D01*
X447600Y-124667D01*
X447700Y-126000D01*
X447600Y-127333D01*
X447200Y-128267D01*
X446700Y-129067D01*
X446100Y-129600D01*
X445300Y-130000D01*
X443300D01*
G01X473000D02*
Y-122000D01*
X471800Y-123600D01*
G01Y-130000D02*
X474200D01*
G01X478800Y-128800D02*
X479400Y-129467D01*
X480100Y-129867D01*
X481000Y-130000D01*
X481900Y-129733D01*
X482600Y-129200D01*
X483100Y-128267D01*
X483200Y-127200D01*
X483000Y-126133D01*
X482500Y-125467D01*
X481800Y-124933D01*
X481100Y-124800D01*
X480400Y-124933D01*
X479500Y-125467D01*
X479800Y-122000D01*
X482500D01*
G54D12*
G01X73363Y1667658D02*
Y1669418D01*
G01X73203Y1667658D02*
Y1669418D01*
G01X73043Y1667658D02*
Y1669418D01*
G01X72883Y1667658D02*
Y1669418D01*
G01X72723Y1667658D02*
Y1669418D01*
G01X72563Y1667658D02*
Y1669418D01*
G01X72403Y1667658D02*
Y1669418D01*
G01X72243Y1667658D02*
Y1669418D01*
G01X72083Y1667658D02*
Y1669418D01*
G01X71923Y1667658D02*
Y1669418D01*
G01X71763Y1667658D02*
Y1669418D01*
G01X71603Y1667658D02*
Y1669418D01*
G01X71443Y1667658D02*
Y1669418D01*
G01X71283Y1667658D02*
Y1669418D01*
G01X71123Y1667658D02*
Y1669418D01*
G01X70963Y1667658D02*
Y1669418D01*
G01X70803Y1667658D02*
Y1669258D01*
G01X70643Y1667658D02*
Y1669258D01*
G01X70483Y1667658D02*
Y1669258D01*
G01X70323Y1667658D02*
Y1671018D01*
G01X70163Y1667658D02*
Y1671018D01*
G01X70003Y1667658D02*
Y1670858D01*
G01X69843Y1667658D02*
Y1670858D01*
G01X69683Y1667658D02*
Y1670698D01*
G01X69523Y1667658D02*
Y1670698D01*
G01X69363Y1667658D02*
Y1670698D01*
G01X69203Y1667658D02*
Y1670538D01*
G01X69043Y1667658D02*
Y1670538D01*
G01X68883Y1667658D02*
Y1670378D01*
G01X68723Y1667658D02*
Y1670378D01*
G01X68563Y1667658D02*
Y1670378D01*
G01X68403Y1667658D02*
Y1670218D01*
G01X73363Y1670538D02*
Y1672138D01*
G01X73203Y1670538D02*
Y1672138D01*
G01X73043Y1670378D02*
Y1672138D01*
G01X72883Y1670378D02*
Y1671978D01*
G01X72723Y1670218D02*
Y1671978D01*
G01X72563Y1670218D02*
Y1671978D01*
G01X72403Y1670218D02*
Y1671818D01*
G01X72243Y1670058D02*
Y1671818D01*
G01X72083Y1670058D02*
Y1671658D01*
G01X71923Y1669898D02*
Y1671658D01*
G01X71763Y1669898D02*
Y1671658D01*
G01X71603Y1669898D02*
Y1671498D01*
G01X71443Y1669738D02*
Y1671498D01*
G01X71283Y1669738D02*
Y1671338D01*
G01X71123Y1669578D02*
Y1671338D01*
G01X70963Y1669578D02*
Y1671338D01*
G01X70803Y1669578D02*
Y1671178D01*
G01X70643Y1669418D02*
Y1671178D01*
G01X70483Y1669418D02*
Y1671018D01*
G01X73363Y1692938D02*
Y1695338D01*
G01Y1685738D02*
Y1687818D01*
G01Y1681738D02*
Y1683498D01*
G01Y1677578D02*
Y1679338D01*
G01Y1674858D02*
Y1676298D01*
G01X73203Y1692938D02*
Y1695498D01*
G01Y1685738D02*
Y1687978D01*
G01Y1681738D02*
Y1683498D01*
G01Y1677578D02*
Y1679338D01*
G01Y1674858D02*
Y1676458D01*
G01X73043Y1692938D02*
Y1695658D01*
G01Y1690858D02*
Y1691178D01*
G01Y1685898D02*
Y1688138D01*
G01Y1681738D02*
Y1683498D01*
G01Y1677578D02*
Y1679338D01*
G01Y1675018D02*
Y1676458D01*
G01X72883Y1697098D02*
Y1697418D01*
G01Y1692938D02*
Y1695978D01*
G01Y1690698D02*
Y1691178D01*
G01Y1685898D02*
Y1688458D01*
G01Y1681738D02*
Y1683498D01*
G01Y1677578D02*
Y1679338D01*
G01Y1675018D02*
Y1676618D01*
G01X72723Y1694858D02*
Y1697418D01*
G01Y1692938D02*
Y1694698D01*
G01Y1690218D02*
Y1691178D01*
G01Y1686058D02*
Y1688778D01*
G01Y1681738D02*
Y1683498D01*
G01Y1677578D02*
Y1679338D01*
G01Y1675018D02*
Y1676618D01*
G01X72563Y1694858D02*
Y1697418D01*
G01Y1692938D02*
Y1694698D01*
G01Y1686218D02*
Y1691178D01*
G01Y1681738D02*
Y1683498D01*
G01Y1677578D02*
Y1679338D01*
G01Y1675178D02*
Y1676618D01*
G01X72403Y1695018D02*
Y1697418D01*
G01Y1692938D02*
Y1694698D01*
G01Y1686378D02*
Y1691178D01*
G01Y1681738D02*
Y1683498D01*
G01Y1677578D02*
Y1679338D01*
G01Y1675178D02*
Y1676778D01*
G01X72243Y1695018D02*
Y1697418D01*
G01Y1692938D02*
Y1694698D01*
G01Y1686538D02*
Y1691178D01*
G01Y1681738D02*
Y1683498D01*
G01Y1677578D02*
Y1679338D01*
G01Y1675338D02*
Y1676778D01*
G01X72083Y1695178D02*
Y1697418D01*
G01Y1692938D02*
Y1694698D01*
G01Y1686698D02*
Y1691178D01*
G01Y1681738D02*
Y1683498D01*
G01Y1677578D02*
Y1679338D01*
G01Y1675338D02*
Y1676938D01*
G01X71923Y1695338D02*
Y1697418D01*
G01Y1692938D02*
Y1694698D01*
G01Y1686858D02*
Y1691178D01*
G01Y1681738D02*
Y1683498D01*
G01Y1677578D02*
Y1679338D01*
G01Y1675498D02*
Y1676938D01*
G01X71763Y1695498D02*
Y1697418D01*
G01Y1692938D02*
Y1694698D01*
G01Y1687178D02*
Y1691178D01*
G01Y1681738D02*
Y1683498D01*
G01Y1677578D02*
Y1679338D01*
G01Y1675498D02*
Y1676938D01*
G01X71603Y1695658D02*
Y1697418D01*
G01Y1692938D02*
Y1694698D01*
G01Y1687498D02*
Y1691178D01*
G01Y1681738D02*
Y1683498D01*
G01Y1677578D02*
Y1679338D01*
G01Y1675498D02*
Y1677098D01*
G01X71443Y1695818D02*
Y1697418D01*
G01Y1692938D02*
Y1694698D01*
G01Y1687818D02*
Y1690858D01*
G01Y1681738D02*
Y1683498D01*
G01Y1677578D02*
Y1679338D01*
G01Y1675658D02*
Y1677098D01*
G01X71283Y1696298D02*
Y1697258D01*
G01Y1688458D02*
Y1690218D01*
G01Y1677578D02*
Y1679338D01*
G01Y1675658D02*
Y1677258D01*
G01X71123Y1677578D02*
Y1679338D01*
G01Y1675818D02*
Y1677258D01*
G01X70963Y1677578D02*
Y1679338D01*
G01Y1675818D02*
Y1677258D01*
G01X70803Y1677578D02*
Y1679338D01*
G01Y1675818D02*
Y1677418D01*
G01X70643Y1677578D02*
Y1679338D01*
G01Y1675978D02*
Y1677418D01*
G01X70483Y1677578D02*
Y1679338D01*
G01Y1675978D02*
Y1677418D01*
G01X70323Y1676138D02*
Y1679338D01*
G01X70163Y1676138D02*
Y1679338D01*
G01X70003Y1676138D02*
Y1679338D01*
G01X69843Y1676298D02*
Y1679338D01*
G01X69683Y1682218D02*
Y1683018D01*
G01Y1676298D02*
Y1679338D01*
G01X69523Y1681898D02*
Y1683338D01*
G01Y1676458D02*
Y1679338D01*
G01X69363Y1681738D02*
Y1683498D01*
G01Y1676458D02*
Y1679338D01*
G01X69203Y1681738D02*
Y1683498D01*
G01Y1676458D02*
Y1679338D01*
G01X69043Y1681578D02*
Y1683658D01*
G01Y1676618D02*
Y1679338D01*
G01X68883Y1681578D02*
Y1683658D01*
G01Y1676618D02*
Y1679338D01*
G01X68723Y1681578D02*
Y1683658D01*
G01Y1676778D02*
Y1679338D01*
G01X68563Y1681578D02*
Y1683658D01*
G01Y1676778D02*
Y1679338D01*
G01X68403Y1681738D02*
Y1683498D01*
G01Y1676778D02*
Y1679338D01*
G01X68243Y1681738D02*
Y1683498D01*
G01X68083Y1681898D02*
Y1683338D01*
G01X67923Y1682218D02*
Y1683018D01*
G01X73363Y1698538D02*
Y1700618D01*
G01Y1719498D02*
Y1721418D01*
G01Y1714218D02*
Y1716298D01*
G01Y1707338D02*
Y1709098D01*
G01Y1703818D02*
Y1705738D01*
G01X73203Y1719338D02*
Y1721418D01*
G01Y1714378D02*
Y1716298D01*
G01Y1707338D02*
Y1709098D01*
G01Y1703658D02*
Y1705738D01*
G01Y1698698D02*
Y1700618D01*
G01X73043Y1719178D02*
Y1721258D01*
G01Y1714378D02*
Y1716618D01*
G01Y1707338D02*
Y1709258D01*
G01Y1703498D02*
Y1705578D01*
G01Y1698698D02*
Y1700938D01*
G01X72883Y1718858D02*
Y1721258D01*
G01Y1714538D02*
Y1716778D01*
G01Y1711818D02*
Y1712298D01*
G01Y1707498D02*
Y1709418D01*
G01Y1703178D02*
Y1705578D01*
G01Y1698858D02*
Y1701098D01*
G01X72723Y1722698D02*
Y1727998D01*
G01Y1718538D02*
Y1721098D01*
G01Y1714698D02*
Y1717258D01*
G01Y1711338D02*
Y1712298D01*
G01Y1707498D02*
Y1709738D01*
G01Y1702858D02*
Y1705418D01*
G01Y1699018D02*
Y1701578D01*
G01X72563Y1722698D02*
Y1727998D01*
G01Y1714698D02*
Y1720938D01*
G01Y1707658D02*
Y1712298D01*
G01Y1699018D02*
Y1705258D01*
G01X72403Y1722698D02*
Y1727998D01*
G01Y1714858D02*
Y1720938D01*
G01Y1707658D02*
Y1712298D01*
G01Y1699178D02*
Y1705258D01*
G01X72243Y1722698D02*
Y1727998D01*
G01Y1715018D02*
Y1720778D01*
G01Y1707818D02*
Y1712298D01*
G01Y1699338D02*
Y1705098D01*
G01X72083Y1722698D02*
Y1727498D01*
G01Y1715178D02*
Y1720618D01*
G01Y1707978D02*
Y1712298D01*
G01Y1699498D02*
Y1704938D01*
G01X71923Y1722698D02*
Y1727998D01*
G01Y1715498D02*
Y1720298D01*
G01Y1708138D02*
Y1712298D01*
G01Y1699818D02*
Y1704618D01*
G01X71763Y1722698D02*
Y1727498D01*
G01Y1715658D02*
Y1720138D01*
G01Y1708298D02*
Y1712298D01*
G01Y1699978D02*
Y1704458D01*
G01X71603Y1722698D02*
Y1727998D01*
G01Y1715978D02*
Y1719818D01*
G01Y1708618D02*
Y1712298D01*
G01Y1700298D02*
Y1704138D01*
G01X71443Y1722698D02*
Y1727998D01*
G01Y1716458D02*
Y1719498D01*
G01Y1709098D02*
Y1712138D01*
G01Y1700778D02*
Y1703818D01*
G01X71283Y1717098D02*
Y1718858D01*
G01Y1709578D02*
Y1711498D01*
G01Y1701418D02*
Y1703178D01*
G01X73363Y1724138D02*
Y1725738D01*
G01X73203Y1724138D02*
Y1725738D01*
G01X73043Y1724138D02*
Y1725738D01*
G01X72883Y1724138D02*
Y1725738D01*
G01X72723Y1727978D02*
Y1732778D01*
G01X72563Y1727978D02*
Y1732778D01*
G01X72403Y1727978D02*
Y1732778D01*
G01X72243Y1727978D02*
Y1732778D01*
G01X72083Y1727978D02*
Y1732778D01*
G01X71923Y1727978D02*
Y1732778D01*
G01X71763Y1727978D02*
Y1732778D01*
G01X71603Y1727978D02*
Y1732778D01*
G01X71443Y1727978D02*
Y1732778D01*
G01X71283Y1724138D02*
Y1725738D01*
G01X71123Y1724138D02*
Y1725738D01*
G01X70963Y1724138D02*
Y1725738D01*
G01X70803Y1724138D02*
Y1725738D01*
G01X70643Y1724138D02*
Y1725738D01*
G01X70483Y1724138D02*
Y1725738D01*
G01X70323Y1724138D02*
Y1725738D01*
G01X70163Y1724138D02*
Y1725738D01*
G01X70003Y1724138D02*
Y1725738D01*
G01X69843Y1724138D02*
Y1725898D01*
G01X69683Y1724138D02*
Y1725898D01*
G01X69523Y1724138D02*
Y1725898D01*
G01X69363Y1724138D02*
Y1726058D01*
G01X69203Y1724138D02*
Y1726218D01*
G01X69043Y1727658D02*
Y1727818D01*
G01Y1724298D02*
Y1726538D01*
G01X68883Y1724298D02*
Y1727818D01*
G01X68723Y1724458D02*
Y1727818D01*
G01X68563Y1724618D02*
Y1727818D01*
G01X68403Y1724618D02*
Y1727818D01*
G01X68243Y1724778D02*
Y1727818D01*
G01X68083Y1725098D02*
Y1727818D01*
G01X67923Y1725258D02*
Y1727818D01*
G01X67763Y1725578D02*
Y1727818D01*
G01X67603Y1726058D02*
Y1727658D01*
G01X73363Y1729258D02*
Y1731018D01*
G01X73203Y1729258D02*
Y1731018D01*
G01X73043Y1729258D02*
Y1731018D01*
G01X72883Y1729258D02*
Y1731018D01*
G01X71283Y1729258D02*
Y1731018D01*
G01X71123Y1729258D02*
Y1731018D01*
G01X70963Y1729258D02*
Y1731018D01*
G01X70803Y1729258D02*
Y1731018D01*
G01X70643Y1729258D02*
Y1731018D01*
G01X70483Y1729258D02*
Y1731018D01*
G01X70323Y1729258D02*
Y1731018D01*
G01X70163Y1729258D02*
Y1731018D01*
G01X70003Y1729258D02*
Y1731018D01*
G01X69843Y1729258D02*
Y1731018D01*
G01X69683Y1729258D02*
Y1731018D01*
G01X69523Y1729578D02*
Y1731018D01*
G01X69363Y1730218D02*
Y1731018D01*
G01X69203Y1730698D02*
Y1731018D01*
G01X78963Y1667658D02*
Y1669418D01*
G01X78803Y1667658D02*
Y1669418D01*
G01X78643Y1667658D02*
Y1669418D01*
G01X78483Y1667658D02*
Y1669418D01*
G01X78323Y1667658D02*
Y1669418D01*
G01X78163Y1667658D02*
Y1669418D01*
G01X78003Y1667658D02*
Y1669418D01*
G01X77843Y1667658D02*
Y1669418D01*
G01X77683Y1667658D02*
Y1669418D01*
G01X77523Y1667658D02*
Y1669418D01*
G01X77363Y1667658D02*
Y1669418D01*
G01X77203Y1667658D02*
Y1669418D01*
G01X77043Y1667658D02*
Y1669418D01*
G01X76883Y1667658D02*
Y1669418D01*
G01X76723Y1667658D02*
Y1669418D01*
G01X76563Y1667658D02*
Y1669418D01*
G01X76403Y1667658D02*
Y1669418D01*
G01X76243Y1667658D02*
Y1669418D01*
G01X76083Y1667658D02*
Y1669418D01*
G01X75923Y1667658D02*
Y1669418D01*
G01X75763Y1667658D02*
Y1669418D01*
G01X75603Y1667658D02*
Y1669418D01*
G01X75443Y1667658D02*
Y1669418D01*
G01X75283Y1667658D02*
Y1669418D01*
G01X75123Y1667658D02*
Y1669418D01*
G01X74963Y1667658D02*
Y1669418D01*
G01X74803Y1667658D02*
Y1669418D01*
G01X74643Y1667658D02*
Y1669418D01*
G01X74483Y1667658D02*
Y1669418D01*
G01X74323Y1667658D02*
Y1669418D01*
G01X74163Y1667658D02*
Y1669418D01*
G01X74003Y1667658D02*
Y1669418D01*
G01X73843Y1667658D02*
Y1669418D01*
G01X73683Y1667658D02*
Y1669418D01*
G01X73523Y1667658D02*
Y1669418D01*
G01X78963Y1672778D02*
Y1674058D01*
G01X78803Y1672778D02*
Y1674218D01*
G01X78643Y1672778D02*
Y1674218D01*
G01X78483Y1672618D02*
Y1674218D01*
G01X78323Y1672618D02*
Y1674378D01*
G01X78163Y1672458D02*
Y1674378D01*
G01X78003Y1672458D02*
Y1674538D01*
G01X77843Y1672298D02*
Y1674538D01*
G01X77683Y1672298D02*
Y1674538D01*
G01X77523Y1672298D02*
Y1674698D01*
G01X77363Y1672138D02*
Y1674698D01*
G01X77203Y1672138D02*
Y1674858D01*
G01X77043Y1671978D02*
Y1674858D01*
G01X76883Y1671978D02*
Y1674858D01*
G01X76723Y1671978D02*
Y1675018D01*
G01X76563Y1673578D02*
Y1675018D01*
G01Y1671818D02*
Y1673418D01*
G01X76403Y1673578D02*
Y1675178D01*
G01Y1671818D02*
Y1673418D01*
G01X76243Y1673738D02*
Y1675178D01*
G01Y1671658D02*
Y1673418D01*
G01X76083Y1673738D02*
Y1675338D01*
G01Y1671658D02*
Y1673258D01*
G01X75923Y1673738D02*
Y1675338D01*
G01Y1671658D02*
Y1673258D01*
G01X75763Y1673898D02*
Y1675338D01*
G01Y1671498D02*
Y1673098D01*
G01X75603Y1673898D02*
Y1675498D01*
G01Y1671498D02*
Y1673098D01*
G01X75443Y1674058D02*
Y1675498D01*
G01Y1671338D02*
Y1673098D01*
G01X75283Y1674058D02*
Y1675658D01*
G01Y1671338D02*
Y1672938D01*
G01X75123Y1674058D02*
Y1675658D01*
G01Y1671338D02*
Y1672938D01*
G01X74963Y1674218D02*
Y1675658D01*
G01Y1671178D02*
Y1672778D01*
G01X74803Y1674218D02*
Y1675818D01*
G01Y1671178D02*
Y1672778D01*
G01X74643Y1674378D02*
Y1675818D01*
G01Y1671018D02*
Y1672778D01*
G01X74483Y1674378D02*
Y1675978D01*
G01Y1671018D02*
Y1672618D01*
G01X74323Y1674378D02*
Y1675978D01*
G01Y1671018D02*
Y1672618D01*
G01X74163Y1670858D02*
Y1672458D01*
G01X74003Y1670858D02*
Y1672458D01*
G01X73843Y1670698D02*
Y1672458D01*
G01X73683Y1670698D02*
Y1672298D01*
G01X73523Y1670698D02*
Y1672298D01*
G01X79123Y1688138D02*
Y1689898D01*
G01X78963Y1692938D02*
Y1694698D01*
G01Y1687658D02*
Y1690538D01*
G01Y1681738D02*
Y1683498D01*
G01Y1677578D02*
Y1679338D01*
G01X78803Y1692938D02*
Y1694698D01*
G01Y1687178D02*
Y1691018D01*
G01Y1681738D02*
Y1683498D01*
G01Y1677578D02*
Y1679338D01*
G01X78643Y1692938D02*
Y1694698D01*
G01Y1687018D02*
Y1691178D01*
G01Y1681738D02*
Y1683498D01*
G01Y1677578D02*
Y1679338D01*
G01X78483Y1692938D02*
Y1694698D01*
G01Y1686698D02*
Y1691178D01*
G01Y1681738D02*
Y1683498D01*
G01Y1677578D02*
Y1679338D01*
G01X78323Y1692938D02*
Y1694698D01*
G01Y1686538D02*
Y1691178D01*
G01Y1681738D02*
Y1683498D01*
G01Y1677578D02*
Y1679338D01*
G01X78163Y1692938D02*
Y1694698D01*
G01Y1686378D02*
Y1691178D01*
G01Y1681738D02*
Y1683498D01*
G01Y1677578D02*
Y1679338D01*
G01X78003Y1692938D02*
Y1694698D01*
G01Y1686218D02*
Y1691178D01*
G01Y1681738D02*
Y1683498D01*
G01Y1677578D02*
Y1679338D01*
G01X77843Y1692938D02*
Y1694698D01*
G01Y1686058D02*
Y1691178D01*
G01Y1681738D02*
Y1683498D01*
G01Y1677578D02*
Y1679338D01*
G01X77683Y1692938D02*
Y1694698D01*
G01Y1690218D02*
Y1691178D01*
G01Y1685898D02*
Y1688778D01*
G01Y1681738D02*
Y1683498D01*
G01Y1677578D02*
Y1679338D01*
G01X77523Y1692938D02*
Y1694698D01*
G01Y1690538D02*
Y1691178D01*
G01Y1685898D02*
Y1688298D01*
G01Y1681738D02*
Y1683498D01*
G01Y1677578D02*
Y1679338D01*
G01X77363Y1692938D02*
Y1694698D01*
G01Y1690858D02*
Y1691178D01*
G01Y1685738D02*
Y1687978D01*
G01Y1681738D02*
Y1683498D01*
G01Y1677578D02*
Y1679338D01*
G01X77203Y1692938D02*
Y1694698D01*
G01Y1685578D02*
Y1687818D01*
G01Y1681738D02*
Y1683498D01*
G01Y1677578D02*
Y1679338D01*
G01X77043Y1692938D02*
Y1694698D01*
G01Y1685578D02*
Y1687658D01*
G01Y1681738D02*
Y1683498D01*
G01Y1677578D02*
Y1679338D01*
G01X76883Y1692938D02*
Y1694698D01*
G01Y1685578D02*
Y1687498D01*
G01Y1681738D02*
Y1683498D01*
G01Y1677578D02*
Y1679338D01*
G01X76723Y1692938D02*
Y1694698D01*
G01Y1685418D02*
Y1687338D01*
G01Y1681738D02*
Y1683498D01*
G01Y1677578D02*
Y1679338D01*
G01X76563Y1692938D02*
Y1694698D01*
G01Y1685418D02*
Y1687338D01*
G01Y1681738D02*
Y1683498D01*
G01Y1677578D02*
Y1679338D01*
G01X76403Y1692938D02*
Y1694698D01*
G01Y1685418D02*
Y1687178D01*
G01Y1681738D02*
Y1683498D01*
G01Y1677578D02*
Y1679338D01*
G01X76243Y1692938D02*
Y1694698D01*
G01Y1685418D02*
Y1687178D01*
G01Y1681738D02*
Y1683498D01*
G01Y1677578D02*
Y1679338D01*
G01X76083Y1692938D02*
Y1694698D01*
G01Y1685258D02*
Y1687178D01*
G01Y1681738D02*
Y1683498D01*
G01Y1677578D02*
Y1679338D01*
G01X75923Y1692938D02*
Y1694698D01*
G01Y1685258D02*
Y1687018D01*
G01Y1681738D02*
Y1683498D01*
G01Y1677578D02*
Y1679338D01*
G01X75763Y1692938D02*
Y1694698D01*
G01Y1685258D02*
Y1687018D01*
G01Y1681738D02*
Y1683498D01*
G01Y1677578D02*
Y1679338D01*
G01X75603Y1692938D02*
Y1694698D01*
G01Y1685258D02*
Y1687018D01*
G01Y1681738D02*
Y1683498D01*
G01Y1677578D02*
Y1679338D01*
G01X75443Y1692938D02*
Y1694698D01*
G01Y1685258D02*
Y1687018D01*
G01Y1681738D02*
Y1683498D01*
G01Y1677578D02*
Y1679338D01*
G01X75283Y1692938D02*
Y1694698D01*
G01Y1685258D02*
Y1687018D01*
G01Y1681738D02*
Y1683498D01*
G01Y1677578D02*
Y1679338D01*
G01X75123Y1692938D02*
Y1694698D01*
G01Y1685258D02*
Y1687018D01*
G01Y1681738D02*
Y1683498D01*
G01Y1677578D02*
Y1679338D01*
G01X74963Y1692938D02*
Y1694698D01*
G01Y1685258D02*
Y1687018D01*
G01Y1681738D02*
Y1683498D01*
G01Y1677578D02*
Y1679338D01*
G01X74803Y1692938D02*
Y1694698D01*
G01Y1685258D02*
Y1687018D01*
G01Y1681738D02*
Y1683498D01*
G01Y1677578D02*
Y1679338D01*
G01X74643Y1692938D02*
Y1694698D01*
G01Y1685258D02*
Y1687018D01*
G01Y1681738D02*
Y1683498D01*
G01Y1677578D02*
Y1679338D01*
G01X74483Y1692938D02*
Y1694858D01*
G01Y1685258D02*
Y1687178D01*
G01Y1681738D02*
Y1683498D01*
G01Y1677578D02*
Y1679338D01*
G01X74323Y1692938D02*
Y1694858D01*
G01Y1685418D02*
Y1687178D01*
G01Y1681738D02*
Y1683498D01*
G01Y1677578D02*
Y1679338D01*
G01X74163Y1692938D02*
Y1694858D01*
G01Y1685418D02*
Y1687178D01*
G01Y1681738D02*
Y1683498D01*
G01Y1677578D02*
Y1679338D01*
G01Y1674538D02*
Y1675978D01*
G01X74003Y1692938D02*
Y1695018D01*
G01Y1685418D02*
Y1687338D01*
G01Y1681738D02*
Y1683498D01*
G01Y1677578D02*
Y1679338D01*
G01Y1674538D02*
Y1676138D01*
G01X73843Y1692938D02*
Y1695018D01*
G01Y1685418D02*
Y1687338D01*
G01Y1681738D02*
Y1683498D01*
G01Y1677578D02*
Y1679338D01*
G01Y1674698D02*
Y1676138D01*
G01X73683Y1692938D02*
Y1695178D01*
G01Y1685578D02*
Y1687498D01*
G01Y1681738D02*
Y1683498D01*
G01Y1677578D02*
Y1679338D01*
G01Y1674698D02*
Y1676298D01*
G01X73523Y1692938D02*
Y1695178D01*
G01Y1685578D02*
Y1687658D01*
G01Y1681738D02*
Y1683498D01*
G01Y1677578D02*
Y1679338D01*
G01Y1674698D02*
Y1676298D01*
G01X77043Y1698538D02*
Y1700618D01*
G01X76883Y1698538D02*
Y1700458D01*
G01X76723Y1698378D02*
Y1700298D01*
G01X76563Y1698378D02*
Y1700298D01*
G01X76403Y1698378D02*
Y1700138D01*
G01X76243Y1698378D02*
Y1700138D01*
G01X76083Y1698218D02*
Y1700138D01*
G01X75923Y1698218D02*
Y1699978D01*
G01X75763Y1698218D02*
Y1699978D01*
G01X75603Y1698218D02*
Y1699978D01*
G01X75443Y1698218D02*
Y1699978D01*
G01X75283Y1698218D02*
Y1699978D01*
G01X75123Y1698218D02*
Y1699978D01*
G01X74963Y1698218D02*
Y1699978D01*
G01X74803Y1698218D02*
Y1699978D01*
G01X74643Y1698218D02*
Y1699978D01*
G01X74483Y1698218D02*
Y1699978D01*
G01X74323Y1698378D02*
Y1700138D01*
G01X74163Y1698378D02*
Y1700138D01*
G01X74003Y1698378D02*
Y1700138D01*
G01X73843Y1698378D02*
Y1700298D01*
G01X73683Y1698538D02*
Y1700298D01*
G01X73523Y1698538D02*
Y1700458D01*
G01X79123Y1716938D02*
Y1718698D01*
G01Y1708618D02*
Y1710378D01*
G01Y1701258D02*
Y1703018D01*
G01X78963Y1716298D02*
Y1719338D01*
G01Y1707978D02*
Y1711178D01*
G01Y1700618D02*
Y1703658D01*
G01X78803Y1715818D02*
Y1719658D01*
G01Y1707498D02*
Y1711498D01*
G01Y1700138D02*
Y1703978D01*
G01X78643Y1715658D02*
Y1719978D01*
G01Y1707338D02*
Y1711818D01*
G01Y1699978D02*
Y1704298D01*
G01X78483Y1715338D02*
Y1720298D01*
G01Y1707338D02*
Y1711978D01*
G01Y1699658D02*
Y1704618D01*
G01X78323Y1715178D02*
Y1720458D01*
G01Y1707338D02*
Y1712138D01*
G01Y1699498D02*
Y1704778D01*
G01X78163Y1715018D02*
Y1720618D01*
G01Y1707338D02*
Y1712298D01*
G01Y1699338D02*
Y1704938D01*
G01X78003Y1714858D02*
Y1720778D01*
G01Y1707338D02*
Y1712458D01*
G01Y1699178D02*
Y1705098D01*
G01X77843Y1714698D02*
Y1720938D01*
G01Y1707338D02*
Y1712458D01*
G01Y1699018D02*
Y1705258D01*
G01X77683Y1718538D02*
Y1721098D01*
G01Y1714538D02*
Y1717258D01*
G01Y1710378D02*
Y1712618D01*
G01Y1707338D02*
Y1708778D01*
G01Y1702858D02*
Y1705418D01*
G01Y1698858D02*
Y1701578D01*
G01X77523Y1718858D02*
Y1721098D01*
G01Y1714538D02*
Y1716778D01*
G01Y1710698D02*
Y1712618D01*
G01Y1707338D02*
Y1708298D01*
G01Y1703178D02*
Y1705418D01*
G01Y1698858D02*
Y1701098D01*
G01X77363Y1719178D02*
Y1721258D01*
G01Y1714378D02*
Y1716618D01*
G01Y1710858D02*
Y1712778D01*
G01Y1707338D02*
Y1707978D01*
G01Y1703498D02*
Y1705578D01*
G01Y1698698D02*
Y1700938D01*
G01X77203Y1719338D02*
Y1721258D01*
G01Y1714378D02*
Y1716298D01*
G01Y1711018D02*
Y1712778D01*
G01Y1707338D02*
Y1707658D01*
G01Y1703658D02*
Y1705578D01*
G01Y1698698D02*
Y1700618D01*
G01X77043Y1719498D02*
Y1721418D01*
G01Y1714218D02*
Y1716298D01*
G01Y1711018D02*
Y1712778D01*
G01Y1703818D02*
Y1705738D01*
G01X76883Y1719658D02*
Y1721418D01*
G01Y1714218D02*
Y1716138D01*
G01Y1711018D02*
Y1712778D01*
G01Y1703978D02*
Y1705738D01*
G01X76723Y1719658D02*
Y1721578D01*
G01Y1714058D02*
Y1715978D01*
G01Y1711018D02*
Y1712778D01*
G01Y1703978D02*
Y1705898D01*
G01X76563Y1719818D02*
Y1721578D01*
G01Y1714058D02*
Y1715978D01*
G01Y1710858D02*
Y1712778D01*
G01Y1704138D02*
Y1705898D01*
G01X76403Y1719818D02*
Y1721578D01*
G01Y1714058D02*
Y1715818D01*
G01Y1710858D02*
Y1712778D01*
G01Y1704138D02*
Y1705898D01*
G01X76243Y1719818D02*
Y1721578D01*
G01Y1714058D02*
Y1715818D01*
G01Y1710538D02*
Y1712618D01*
G01Y1704138D02*
Y1705898D01*
G01X76083Y1719978D02*
Y1721738D01*
G01Y1713898D02*
Y1715818D01*
G01Y1710378D02*
Y1712618D01*
G01Y1704298D02*
Y1706058D01*
G01X75923Y1719978D02*
Y1721738D01*
G01Y1713898D02*
Y1715658D01*
G01Y1709898D02*
Y1712458D01*
G01Y1704298D02*
Y1706058D01*
G01X75763Y1719978D02*
Y1721738D01*
G01Y1713898D02*
Y1715658D01*
G01Y1709418D02*
Y1712458D01*
G01Y1704298D02*
Y1706058D01*
G01X75603Y1719978D02*
Y1721738D01*
G01Y1713898D02*
Y1715658D01*
G01Y1709098D02*
Y1712298D01*
G01Y1704298D02*
Y1706058D01*
G01X75443Y1719978D02*
Y1721738D01*
G01Y1713898D02*
Y1715658D01*
G01Y1708778D02*
Y1712138D01*
G01Y1704298D02*
Y1706058D01*
G01X75283Y1719978D02*
Y1721738D01*
G01Y1713898D02*
Y1715658D01*
G01Y1708458D02*
Y1711978D01*
G01Y1704298D02*
Y1706058D01*
G01X75123Y1719978D02*
Y1721738D01*
G01Y1713898D02*
Y1715658D01*
G01Y1708138D02*
Y1711658D01*
G01Y1704298D02*
Y1706058D01*
G01X74963Y1719978D02*
Y1721738D01*
G01Y1713898D02*
Y1715658D01*
G01Y1707978D02*
Y1711498D01*
G01Y1704298D02*
Y1706058D01*
G01X74803Y1719978D02*
Y1721738D01*
G01Y1713898D02*
Y1715658D01*
G01Y1707818D02*
Y1711178D01*
G01Y1704298D02*
Y1706058D01*
G01X74643Y1719978D02*
Y1721738D01*
G01Y1713898D02*
Y1715658D01*
G01Y1707658D02*
Y1710698D01*
G01Y1704298D02*
Y1706058D01*
G01X74483Y1719978D02*
Y1721738D01*
G01Y1713898D02*
Y1715658D01*
G01Y1707658D02*
Y1710378D01*
G01Y1704298D02*
Y1706058D01*
G01X74323Y1719818D02*
Y1721738D01*
G01Y1714058D02*
Y1715818D01*
G01Y1707498D02*
Y1709898D01*
G01Y1704138D02*
Y1706058D01*
G01X74163Y1719818D02*
Y1721738D01*
G01Y1714058D02*
Y1715818D01*
G01Y1707498D02*
Y1709578D01*
G01Y1704138D02*
Y1706058D01*
G01X74003Y1719818D02*
Y1721578D01*
G01Y1714058D02*
Y1715818D01*
G01Y1707498D02*
Y1709258D01*
G01Y1704138D02*
Y1705898D01*
G01X73843Y1719818D02*
Y1721578D01*
G01Y1714058D02*
Y1715978D01*
G01Y1707338D02*
Y1709258D01*
G01Y1704138D02*
Y1705898D01*
G01X73683Y1719658D02*
Y1721578D01*
G01Y1714218D02*
Y1715978D01*
G01Y1707338D02*
Y1709098D01*
G01Y1703978D02*
Y1705898D01*
G01X73523Y1719658D02*
Y1721578D01*
G01Y1714218D02*
Y1716138D01*
G01Y1707338D02*
Y1709098D01*
G01Y1703978D02*
Y1705898D01*
G01X78963Y1724138D02*
Y1725738D01*
G01X78803Y1724138D02*
Y1725738D01*
G01X78643Y1724138D02*
Y1725738D01*
G01X78483Y1724138D02*
Y1725738D01*
G01X78323Y1724138D02*
Y1725738D01*
G01X78163Y1724138D02*
Y1725738D01*
G01X78003Y1724138D02*
Y1725738D01*
G01X77843Y1724138D02*
Y1725738D01*
G01X77683Y1724138D02*
Y1725738D01*
G01X77523Y1724138D02*
Y1725738D01*
G01X77363Y1724138D02*
Y1725738D01*
G01X77203Y1724138D02*
Y1725738D01*
G01X77043Y1724138D02*
Y1725738D01*
G01X76883Y1724138D02*
Y1725738D01*
G01X76723Y1724138D02*
Y1725738D01*
G01X76563Y1724138D02*
Y1725738D01*
G01X76403Y1724138D02*
Y1725738D01*
G01X76243Y1724138D02*
Y1725738D01*
G01X76083Y1724138D02*
Y1725738D01*
G01X75923Y1724138D02*
Y1725738D01*
G01X75763Y1724138D02*
Y1725738D01*
G01X75603Y1724138D02*
Y1725738D01*
G01X75443Y1724138D02*
Y1725738D01*
G01X75283Y1724138D02*
Y1725738D01*
G01X75123Y1724138D02*
Y1725738D01*
G01X74963Y1724138D02*
Y1725738D01*
G01X74803Y1724138D02*
Y1725738D01*
G01X74643Y1724138D02*
Y1725738D01*
G01X74483Y1724138D02*
Y1725738D01*
G01X74323Y1724138D02*
Y1725738D01*
G01X74163Y1724138D02*
Y1725738D01*
G01X74003Y1724138D02*
Y1725738D01*
G01X73843Y1724138D02*
Y1725738D01*
G01X73683Y1724138D02*
Y1725738D01*
G01X73523Y1724138D02*
Y1725738D01*
G01X79123Y1730698D02*
Y1732298D01*
G01X78963Y1730218D02*
Y1732778D01*
G01X78803Y1730058D02*
Y1732778D01*
G01X78643Y1729898D02*
Y1732778D01*
G01X78483Y1729738D02*
Y1732778D01*
G01X78323Y1729578D02*
Y1732778D01*
G01X78163Y1729578D02*
Y1732778D01*
G01X78003Y1729418D02*
Y1732778D01*
G01X77843Y1729418D02*
Y1732778D01*
G01X77683Y1732458D02*
Y1732778D01*
G01Y1729418D02*
Y1731498D01*
G01X77523Y1729258D02*
Y1731338D01*
G01X77363Y1729258D02*
Y1731178D01*
G01X77203Y1729258D02*
Y1731178D01*
G01X77043Y1729258D02*
Y1731018D01*
G01X76883Y1729258D02*
Y1731018D01*
G01X76723Y1729258D02*
Y1731018D01*
G01X76563Y1729258D02*
Y1731018D01*
G01X76403Y1729258D02*
Y1731018D01*
G01X76243Y1729258D02*
Y1731018D01*
G01X76083Y1729258D02*
Y1731018D01*
G01X75923Y1729258D02*
Y1731018D01*
G01X75763Y1729258D02*
Y1731018D01*
G01X75603Y1729258D02*
Y1731018D01*
G01X75443Y1729258D02*
Y1731018D01*
G01X75283Y1729258D02*
Y1731018D01*
G01X75123Y1729258D02*
Y1731018D01*
G01X74963Y1729258D02*
Y1731018D01*
G01X74803Y1729258D02*
Y1731018D01*
G01X74643Y1729258D02*
Y1731018D01*
G01X74483Y1729258D02*
Y1731018D01*
G01X74323Y1729258D02*
Y1731018D01*
G01X74163Y1729258D02*
Y1731018D01*
G01X74003Y1729258D02*
Y1731018D01*
G01X73843Y1729258D02*
Y1731018D01*
G01X73683Y1729258D02*
Y1731018D01*
G01X73523Y1729258D02*
Y1731018D01*
M02*
